FILE_TYPE = MACRO_DRAWING;
SET COLOR_WIRE YELLOW;
SET COLOR_PROP MONO;
SET COLOR_DOT WHITE;
SET COLOR_ARC YELLOW;
SET COLOR_BODY GREEN;
SET COLOR_NOTE MONO;
SET PROP_DISPLAY VALUE;
SET PAGE_NUMBER P66;
FORCEADD TAP..1
R 2
(-5550 1625);
FORCEPROP 3 LASTPIN (-5500 1625) SIG_NAME P3E_CPU1_PE3_MP_RXN<0>
J 0
(-5490 1635);
DISPLAY 0.659574 (-5490 1635);
PAINT MONO (-5490 1635);
DISPLAY INVISIBLE (-5490 1635);
FORCEPROP 1 LASTPIN (-5500 1625) BN 0
J 2
(-5488 1633);
DISPLAY 0.617021 (-5488 1633);
PAINT GREEN (-5488 1633);
FORCEPROP 2 LAST CDS_LIB mstr_standard
J 0
(-5550 1625);
PAINT MONO (-5550 1625);
DISPLAY INVISIBLE (-5550 1625);
FORCEPROP 1 LAST BODY_TYPE PLUMBING
J 2
(-5550 1675);
DISPLAY 1.446809 (-5550 1675);
PAINT GREEN (-5550 1675);
DISPLAY INVISIBLE (-5550 1675);
FORCEPROP 1 LAST HDL_TAP TRUE
J 2
(-5875 1500);
DISPLAY 1.446809 (-5875 1500);
PAINT GREEN (-5875 1500);
DISPLAY INVISIBLE (-5875 1500);
FORCEPROP 1 LAST PATH I10
J 2
(-5548 1625);
DISPLAY 0.872340 (-5548 1625);
PAINT GREEN (-5548 1625);
DISPLAY INVISIBLE (-5548 1625);
FORCEADD TAP..1
R 2
(-5550 1675);
FORCEPROP 3 LASTPIN (-5500 1675) SIG_NAME P3E_CPU1_PE3_MP_RXN<1>
J 0
(-5490 1685);
DISPLAY 0.659574 (-5490 1685);
PAINT MONO (-5490 1685);
DISPLAY INVISIBLE (-5490 1685);
FORCEPROP 1 LASTPIN (-5500 1675) BN 1
J 2
(-5488 1683);
DISPLAY 0.617021 (-5488 1683);
PAINT GREEN (-5488 1683);
FORCEPROP 2 LAST CDS_LIB mstr_standard
J 0
(-5550 1675);
PAINT MONO (-5550 1675);
DISPLAY INVISIBLE (-5550 1675);
FORCEPROP 1 LAST BODY_TYPE PLUMBING
J 2
(-5550 1725);
DISPLAY 1.446809 (-5550 1725);
PAINT GREEN (-5550 1725);
DISPLAY INVISIBLE (-5550 1725);
FORCEPROP 1 LAST HDL_TAP TRUE
J 2
(-5875 1550);
DISPLAY 1.446809 (-5875 1550);
PAINT GREEN (-5875 1550);
DISPLAY INVISIBLE (-5875 1550);
FORCEPROP 1 LAST PATH I11
J 2
(-5548 1675);
DISPLAY 0.872340 (-5548 1675);
PAINT GREEN (-5548 1675);
DISPLAY INVISIBLE (-5548 1675);
FORCEADD TAP..1
R 2
(-5550 1725);
FORCEPROP 3 LASTPIN (-5500 1725) SIG_NAME P3E_CPU1_PE3_MP_RXN<2>
J 0
(-5490 1735);
DISPLAY 0.659574 (-5490 1735);
PAINT MONO (-5490 1735);
DISPLAY INVISIBLE (-5490 1735);
FORCEPROP 1 LASTPIN (-5500 1725) BN 2
J 2
(-5488 1733);
DISPLAY 0.617021 (-5488 1733);
PAINT GREEN (-5488 1733);
FORCEPROP 2 LAST CDS_LIB mstr_standard
J 0
(-5550 1725);
PAINT MONO (-5550 1725);
DISPLAY INVISIBLE (-5550 1725);
FORCEPROP 1 LAST BODY_TYPE PLUMBING
J 2
(-5550 1775);
DISPLAY 1.446809 (-5550 1775);
PAINT GREEN (-5550 1775);
DISPLAY INVISIBLE (-5550 1775);
FORCEPROP 1 LAST HDL_TAP TRUE
J 2
(-5875 1600);
DISPLAY 1.446809 (-5875 1600);
PAINT GREEN (-5875 1600);
DISPLAY INVISIBLE (-5875 1600);
FORCEPROP 1 LAST PATH I12
J 2
(-5548 1725);
DISPLAY 0.872340 (-5548 1725);
PAINT GREEN (-5548 1725);
DISPLAY INVISIBLE (-5548 1725);
FORCEADD TAP..1
R 2
(-5550 1775);
FORCEPROP 3 LASTPIN (-5500 1775) SIG_NAME P3E_CPU1_PE3_MP_RXN<3>
J 0
(-5490 1785);
DISPLAY 0.659574 (-5490 1785);
PAINT MONO (-5490 1785);
DISPLAY INVISIBLE (-5490 1785);
FORCEPROP 1 LASTPIN (-5500 1775) BN 3
J 2
(-5488 1783);
DISPLAY 0.617021 (-5488 1783);
PAINT GREEN (-5488 1783);
FORCEPROP 2 LAST CDS_LIB mstr_standard
J 0
(-5550 1775);
PAINT MONO (-5550 1775);
DISPLAY INVISIBLE (-5550 1775);
FORCEPROP 1 LAST BODY_TYPE PLUMBING
J 2
(-5550 1825);
DISPLAY 1.446809 (-5550 1825);
PAINT GREEN (-5550 1825);
DISPLAY INVISIBLE (-5550 1825);
FORCEPROP 1 LAST HDL_TAP TRUE
J 2
(-5875 1650);
DISPLAY 1.446809 (-5875 1650);
PAINT GREEN (-5875 1650);
DISPLAY INVISIBLE (-5875 1650);
FORCEPROP 1 LAST PATH I13
J 2
(-5548 1775);
DISPLAY 0.872340 (-5548 1775);
PAINT GREEN (-5548 1775);
DISPLAY INVISIBLE (-5548 1775);
FORCEADD TAP..1
R 2
(-5400 1875);
FORCEPROP 3 LASTPIN (-5350 1875) SIG_NAME P3E_CPU1_PE3_MP_RXP<0>
J 0
(-5340 1885);
DISPLAY 0.659574 (-5340 1885);
PAINT MONO (-5340 1885);
DISPLAY INVISIBLE (-5340 1885);
FORCEPROP 1 LASTPIN (-5350 1875) BN 0
J 2
(-5338 1883);
DISPLAY 0.617021 (-5338 1883);
PAINT GREEN (-5338 1883);
FORCEPROP 2 LAST CDS_LIB mstr_standard
J 0
(-5400 1875);
PAINT MONO (-5400 1875);
DISPLAY INVISIBLE (-5400 1875);
FORCEPROP 1 LAST BODY_TYPE PLUMBING
J 2
(-5400 1925);
DISPLAY 1.446809 (-5400 1925);
PAINT GREEN (-5400 1925);
DISPLAY INVISIBLE (-5400 1925);
FORCEPROP 1 LAST HDL_TAP TRUE
J 2
(-5725 1750);
DISPLAY 1.446809 (-5725 1750);
PAINT GREEN (-5725 1750);
DISPLAY INVISIBLE (-5725 1750);
FORCEPROP 1 LAST PATH I14
J 2
(-5398 1875);
DISPLAY 0.872340 (-5398 1875);
PAINT GREEN (-5398 1875);
DISPLAY INVISIBLE (-5398 1875);
FORCEADD TAP..1
R 2
(-5400 1925);
FORCEPROP 3 LASTPIN (-5350 1925) SIG_NAME P3E_CPU1_PE3_MP_RXP<1>
J 0
(-5340 1935);
DISPLAY 0.659574 (-5340 1935);
PAINT MONO (-5340 1935);
DISPLAY INVISIBLE (-5340 1935);
FORCEPROP 1 LASTPIN (-5350 1925) BN 1
J 2
(-5338 1933);
DISPLAY 0.617021 (-5338 1933);
PAINT GREEN (-5338 1933);
FORCEPROP 2 LAST CDS_LIB mstr_standard
J 0
(-5400 1925);
PAINT MONO (-5400 1925);
DISPLAY INVISIBLE (-5400 1925);
FORCEPROP 1 LAST BODY_TYPE PLUMBING
J 2
(-5400 1975);
DISPLAY 1.446809 (-5400 1975);
PAINT GREEN (-5400 1975);
DISPLAY INVISIBLE (-5400 1975);
FORCEPROP 1 LAST HDL_TAP TRUE
J 2
(-5725 1800);
DISPLAY 1.446809 (-5725 1800);
PAINT GREEN (-5725 1800);
DISPLAY INVISIBLE (-5725 1800);
FORCEPROP 1 LAST PATH I15
J 2
(-5398 1925);
DISPLAY 0.872340 (-5398 1925);
PAINT GREEN (-5398 1925);
DISPLAY INVISIBLE (-5398 1925);
FORCEADD TAP..1
R 2
(-5400 1975);
FORCEPROP 3 LASTPIN (-5350 1975) SIG_NAME P3E_CPU1_PE3_MP_RXP<2>
J 0
(-5340 1985);
DISPLAY 0.659574 (-5340 1985);
PAINT MONO (-5340 1985);
DISPLAY INVISIBLE (-5340 1985);
FORCEPROP 1 LASTPIN (-5350 1975) BN 2
J 2
(-5338 1983);
DISPLAY 0.617021 (-5338 1983);
PAINT GREEN (-5338 1983);
FORCEPROP 2 LAST CDS_LIB mstr_standard
J 0
(-5400 1975);
PAINT MONO (-5400 1975);
DISPLAY INVISIBLE (-5400 1975);
FORCEPROP 1 LAST BODY_TYPE PLUMBING
J 2
(-5400 2025);
DISPLAY 1.446809 (-5400 2025);
PAINT GREEN (-5400 2025);
DISPLAY INVISIBLE (-5400 2025);
FORCEPROP 1 LAST HDL_TAP TRUE
J 2
(-5725 1850);
DISPLAY 1.446809 (-5725 1850);
PAINT GREEN (-5725 1850);
DISPLAY INVISIBLE (-5725 1850);
FORCEPROP 1 LAST PATH I16
J 2
(-5398 1975);
DISPLAY 0.872340 (-5398 1975);
PAINT GREEN (-5398 1975);
DISPLAY INVISIBLE (-5398 1975);
FORCEADD TAP..1
R 2
(-5400 2025);
FORCEPROP 3 LASTPIN (-5350 2025) SIG_NAME P3E_CPU1_PE3_MP_RXP<3>
J 0
(-5340 2035);
DISPLAY 0.659574 (-5340 2035);
PAINT MONO (-5340 2035);
DISPLAY INVISIBLE (-5340 2035);
FORCEPROP 1 LASTPIN (-5350 2025) BN 3
J 2
(-5338 2033);
DISPLAY 0.617021 (-5338 2033);
PAINT GREEN (-5338 2033);
FORCEPROP 2 LAST CDS_LIB mstr_standard
J 0
(-5400 2025);
PAINT MONO (-5400 2025);
DISPLAY INVISIBLE (-5400 2025);
FORCEPROP 1 LAST BODY_TYPE PLUMBING
J 2
(-5400 2075);
DISPLAY 1.446809 (-5400 2075);
PAINT GREEN (-5400 2075);
DISPLAY INVISIBLE (-5400 2075);
FORCEPROP 1 LAST HDL_TAP TRUE
J 2
(-5725 1900);
DISPLAY 1.446809 (-5725 1900);
PAINT GREEN (-5725 1900);
DISPLAY INVISIBLE (-5725 1900);
FORCEPROP 1 LAST PATH I17
J 2
(-5398 2025);
DISPLAY 0.872340 (-5398 2025);
PAINT GREEN (-5398 2025);
DISPLAY INVISIBLE (-5398 2025);
FORCEADD TAP..1
R 2
(-5550 2175);
FORCEPROP 3 LASTPIN (-5500 2175) SIG_NAME P3E_CPU1_PE3_MP_RXN<5>
J 0
(-5490 2185);
DISPLAY 0.659574 (-5490 2185);
PAINT MONO (-5490 2185);
DISPLAY INVISIBLE (-5490 2185);
FORCEPROP 1 LASTPIN (-5500 2175) BN 5
J 2
(-5488 2183);
DISPLAY 0.617021 (-5488 2183);
PAINT GREEN (-5488 2183);
FORCEPROP 2 LAST CDS_LIB mstr_standard
J 0
(-5550 2175);
PAINT MONO (-5550 2175);
DISPLAY INVISIBLE (-5550 2175);
FORCEPROP 1 LAST BODY_TYPE PLUMBING
J 2
(-5550 2225);
DISPLAY 1.446809 (-5550 2225);
PAINT GREEN (-5550 2225);
DISPLAY INVISIBLE (-5550 2225);
FORCEPROP 1 LAST HDL_TAP TRUE
J 2
(-5875 2050);
DISPLAY 1.446809 (-5875 2050);
PAINT GREEN (-5875 2050);
DISPLAY INVISIBLE (-5875 2050);
FORCEPROP 1 LAST PATH I18
J 2
(-5548 2175);
DISPLAY 0.872340 (-5548 2175);
PAINT GREEN (-5548 2175);
DISPLAY INVISIBLE (-5548 2175);
FORCEADD TAP..1
R 2
(-5550 2125);
FORCEPROP 3 LASTPIN (-5500 2125) SIG_NAME P3E_CPU1_PE3_MP_RXN<4>
J 0
(-5490 2135);
DISPLAY 0.659574 (-5490 2135);
PAINT MONO (-5490 2135);
DISPLAY INVISIBLE (-5490 2135);
FORCEPROP 1 LASTPIN (-5500 2125) BN 4
J 2
(-5488 2133);
DISPLAY 0.617021 (-5488 2133);
PAINT GREEN (-5488 2133);
FORCEPROP 2 LAST CDS_LIB mstr_standard
J 0
(-5550 2125);
PAINT MONO (-5550 2125);
DISPLAY INVISIBLE (-5550 2125);
FORCEPROP 1 LAST BODY_TYPE PLUMBING
J 2
(-5550 2175);
DISPLAY 1.446809 (-5550 2175);
PAINT GREEN (-5550 2175);
DISPLAY INVISIBLE (-5550 2175);
FORCEPROP 1 LAST HDL_TAP TRUE
J 2
(-5875 2000);
DISPLAY 1.446809 (-5875 2000);
PAINT GREEN (-5875 2000);
DISPLAY INVISIBLE (-5875 2000);
FORCEPROP 1 LAST PATH I19
J 2
(-5548 2125);
DISPLAY 0.872340 (-5548 2125);
PAINT GREEN (-5548 2125);
DISPLAY INVISIBLE (-5548 2125);
FORCEADD TAP..1
R 2
(-5550 2225);
FORCEPROP 3 LASTPIN (-5500 2225) SIG_NAME P3E_CPU1_PE3_MP_RXN<6>
J 0
(-5490 2235);
DISPLAY 0.659574 (-5490 2235);
PAINT MONO (-5490 2235);
DISPLAY INVISIBLE (-5490 2235);
FORCEPROP 1 LASTPIN (-5500 2225) BN 6
J 2
(-5488 2233);
DISPLAY 0.617021 (-5488 2233);
PAINT GREEN (-5488 2233);
FORCEPROP 2 LAST CDS_LIB mstr_standard
J 0
(-5550 2225);
PAINT MONO (-5550 2225);
DISPLAY INVISIBLE (-5550 2225);
FORCEPROP 1 LAST BODY_TYPE PLUMBING
J 2
(-5550 2275);
DISPLAY 1.446809 (-5550 2275);
PAINT GREEN (-5550 2275);
DISPLAY INVISIBLE (-5550 2275);
FORCEPROP 1 LAST HDL_TAP TRUE
J 2
(-5875 2100);
DISPLAY 1.446809 (-5875 2100);
PAINT GREEN (-5875 2100);
DISPLAY INVISIBLE (-5875 2100);
FORCEPROP 1 LAST PATH I20
J 2
(-5548 2225);
DISPLAY 0.872340 (-5548 2225);
PAINT GREEN (-5548 2225);
DISPLAY INVISIBLE (-5548 2225);
FORCEADD TAP..1
R 2
(-5550 2275);
FORCEPROP 3 LASTPIN (-5500 2275) SIG_NAME P3E_CPU1_PE3_MP_RXN<7>
J 0
(-5490 2285);
DISPLAY 0.659574 (-5490 2285);
PAINT MONO (-5490 2285);
DISPLAY INVISIBLE (-5490 2285);
FORCEPROP 1 LASTPIN (-5500 2275) BN 7
J 2
(-5488 2283);
DISPLAY 0.617021 (-5488 2283);
PAINT GREEN (-5488 2283);
FORCEPROP 2 LAST CDS_LIB mstr_standard
J 0
(-5550 2275);
PAINT MONO (-5550 2275);
DISPLAY INVISIBLE (-5550 2275);
FORCEPROP 1 LAST BODY_TYPE PLUMBING
J 2
(-5550 2325);
DISPLAY 1.446809 (-5550 2325);
PAINT GREEN (-5550 2325);
DISPLAY INVISIBLE (-5550 2325);
FORCEPROP 1 LAST HDL_TAP TRUE
J 2
(-5875 2150);
DISPLAY 1.446809 (-5875 2150);
PAINT GREEN (-5875 2150);
DISPLAY INVISIBLE (-5875 2150);
FORCEPROP 1 LAST PATH I21
J 2
(-5548 2275);
DISPLAY 0.872340 (-5548 2275);
PAINT GREEN (-5548 2275);
DISPLAY INVISIBLE (-5548 2275);
FORCEADD TAP..1
R 2
(-5400 2375);
FORCEPROP 3 LASTPIN (-5350 2375) SIG_NAME P3E_CPU1_PE3_MP_RXP<4>
J 0
(-5340 2385);
DISPLAY 0.659574 (-5340 2385);
PAINT MONO (-5340 2385);
DISPLAY INVISIBLE (-5340 2385);
FORCEPROP 1 LASTPIN (-5350 2375) BN 4
J 2
(-5338 2383);
DISPLAY 0.617021 (-5338 2383);
PAINT GREEN (-5338 2383);
FORCEPROP 2 LAST CDS_LIB mstr_standard
J 0
(-5400 2375);
PAINT MONO (-5400 2375);
DISPLAY INVISIBLE (-5400 2375);
FORCEPROP 1 LAST BODY_TYPE PLUMBING
J 2
(-5400 2425);
DISPLAY 1.446809 (-5400 2425);
PAINT GREEN (-5400 2425);
DISPLAY INVISIBLE (-5400 2425);
FORCEPROP 1 LAST HDL_TAP TRUE
J 2
(-5725 2250);
DISPLAY 1.446809 (-5725 2250);
PAINT GREEN (-5725 2250);
DISPLAY INVISIBLE (-5725 2250);
FORCEPROP 1 LAST PATH I22
J 2
(-5398 2375);
DISPLAY 0.872340 (-5398 2375);
PAINT GREEN (-5398 2375);
DISPLAY INVISIBLE (-5398 2375);
FORCEADD TAP..1
R 2
(-5400 2425);
FORCEPROP 3 LASTPIN (-5350 2425) SIG_NAME P3E_CPU1_PE3_MP_RXP<5>
J 0
(-5340 2435);
DISPLAY 0.659574 (-5340 2435);
PAINT MONO (-5340 2435);
DISPLAY INVISIBLE (-5340 2435);
FORCEPROP 1 LASTPIN (-5350 2425) BN 5
J 2
(-5338 2433);
DISPLAY 0.617021 (-5338 2433);
PAINT GREEN (-5338 2433);
FORCEPROP 2 LAST CDS_LIB mstr_standard
J 0
(-5400 2425);
PAINT MONO (-5400 2425);
DISPLAY INVISIBLE (-5400 2425);
FORCEPROP 1 LAST BODY_TYPE PLUMBING
J 2
(-5400 2475);
DISPLAY 1.446809 (-5400 2475);
PAINT GREEN (-5400 2475);
DISPLAY INVISIBLE (-5400 2475);
FORCEPROP 1 LAST HDL_TAP TRUE
J 2
(-5725 2300);
DISPLAY 1.446809 (-5725 2300);
PAINT GREEN (-5725 2300);
DISPLAY INVISIBLE (-5725 2300);
FORCEPROP 1 LAST PATH I23
J 2
(-5398 2425);
DISPLAY 0.872340 (-5398 2425);
PAINT GREEN (-5398 2425);
DISPLAY INVISIBLE (-5398 2425);
FORCEADD TAP..1
R 2
(-5400 2475);
FORCEPROP 3 LASTPIN (-5350 2475) SIG_NAME P3E_CPU1_PE3_MP_RXP<6>
J 0
(-5340 2485);
DISPLAY 0.659574 (-5340 2485);
PAINT MONO (-5340 2485);
DISPLAY INVISIBLE (-5340 2485);
FORCEPROP 1 LASTPIN (-5350 2475) BN 6
J 2
(-5338 2483);
DISPLAY 0.617021 (-5338 2483);
PAINT GREEN (-5338 2483);
FORCEPROP 2 LAST CDS_LIB mstr_standard
J 0
(-5400 2475);
PAINT MONO (-5400 2475);
DISPLAY INVISIBLE (-5400 2475);
FORCEPROP 1 LAST BODY_TYPE PLUMBING
J 2
(-5400 2525);
DISPLAY 1.446809 (-5400 2525);
PAINT GREEN (-5400 2525);
DISPLAY INVISIBLE (-5400 2525);
FORCEPROP 1 LAST HDL_TAP TRUE
J 2
(-5725 2350);
DISPLAY 1.446809 (-5725 2350);
PAINT GREEN (-5725 2350);
DISPLAY INVISIBLE (-5725 2350);
FORCEPROP 1 LAST PATH I24
J 2
(-5398 2475);
DISPLAY 0.872340 (-5398 2475);
PAINT GREEN (-5398 2475);
DISPLAY INVISIBLE (-5398 2475);
FORCEADD TAP..1
R 2
(-5400 2525);
FORCEPROP 3 LASTPIN (-5350 2525) SIG_NAME P3E_CPU1_PE3_MP_RXP<7>
J 0
(-5340 2535);
DISPLAY 0.659574 (-5340 2535);
PAINT MONO (-5340 2535);
DISPLAY INVISIBLE (-5340 2535);
FORCEPROP 1 LASTPIN (-5350 2525) BN 7
J 2
(-5338 2533);
DISPLAY 0.617021 (-5338 2533);
PAINT GREEN (-5338 2533);
FORCEPROP 2 LAST CDS_LIB mstr_standard
J 0
(-5400 2525);
PAINT MONO (-5400 2525);
DISPLAY INVISIBLE (-5400 2525);
FORCEPROP 1 LAST BODY_TYPE PLUMBING
J 2
(-5400 2575);
DISPLAY 1.446809 (-5400 2575);
PAINT GREEN (-5400 2575);
DISPLAY INVISIBLE (-5400 2575);
FORCEPROP 1 LAST HDL_TAP TRUE
J 2
(-5725 2400);
DISPLAY 1.446809 (-5725 2400);
PAINT GREEN (-5725 2400);
DISPLAY INVISIBLE (-5725 2400);
FORCEPROP 1 LAST PATH I25
J 2
(-5398 2525);
DISPLAY 0.872340 (-5398 2525);
PAINT GREEN (-5398 2525);
DISPLAY INVISIBLE (-5398 2525);
FORCEADD TAP..1
R 2
(-5550 2675);
FORCEPROP 3 LASTPIN (-5500 2675) SIG_NAME P3E_CPU1_PE3_MP_RXN<9>
J 0
(-5490 2685);
DISPLAY 0.659574 (-5490 2685);
PAINT MONO (-5490 2685);
DISPLAY INVISIBLE (-5490 2685);
FORCEPROP 1 LASTPIN (-5500 2675) BN 9
J 2
(-5488 2683);
DISPLAY 0.617021 (-5488 2683);
PAINT GREEN (-5488 2683);
FORCEPROP 2 LAST CDS_LIB mstr_standard
J 0
(-5550 2675);
PAINT MONO (-5550 2675);
DISPLAY INVISIBLE (-5550 2675);
FORCEPROP 1 LAST BODY_TYPE PLUMBING
J 2
(-5550 2725);
DISPLAY 1.446809 (-5550 2725);
PAINT GREEN (-5550 2725);
DISPLAY INVISIBLE (-5550 2725);
FORCEPROP 1 LAST HDL_TAP TRUE
J 2
(-5875 2550);
DISPLAY 1.446809 (-5875 2550);
PAINT GREEN (-5875 2550);
DISPLAY INVISIBLE (-5875 2550);
FORCEPROP 1 LAST PATH I26
J 2
(-5548 2675);
DISPLAY 0.872340 (-5548 2675);
PAINT GREEN (-5548 2675);
DISPLAY INVISIBLE (-5548 2675);
FORCEADD TAP..1
R 2
(-5550 2625);
FORCEPROP 3 LASTPIN (-5500 2625) SIG_NAME P3E_CPU1_PE3_MP_RXN<8>
J 0
(-5490 2635);
DISPLAY 0.659574 (-5490 2635);
PAINT MONO (-5490 2635);
DISPLAY INVISIBLE (-5490 2635);
FORCEPROP 1 LASTPIN (-5500 2625) BN 8
J 2
(-5488 2633);
DISPLAY 0.617021 (-5488 2633);
PAINT GREEN (-5488 2633);
FORCEPROP 2 LAST CDS_LIB mstr_standard
J 0
(-5550 2625);
PAINT MONO (-5550 2625);
DISPLAY INVISIBLE (-5550 2625);
FORCEPROP 1 LAST BODY_TYPE PLUMBING
J 2
(-5550 2675);
DISPLAY 1.446809 (-5550 2675);
PAINT GREEN (-5550 2675);
DISPLAY INVISIBLE (-5550 2675);
FORCEPROP 1 LAST HDL_TAP TRUE
J 2
(-5875 2500);
DISPLAY 1.446809 (-5875 2500);
PAINT GREEN (-5875 2500);
DISPLAY INVISIBLE (-5875 2500);
FORCEPROP 1 LAST PATH I27
J 2
(-5548 2625);
DISPLAY 0.872340 (-5548 2625);
PAINT GREEN (-5548 2625);
DISPLAY INVISIBLE (-5548 2625);
FORCEADD TAP..1
R 2
(-5550 2725);
FORCEPROP 3 LASTPIN (-5500 2725) SIG_NAME P3E_CPU1_PE3_MP_RXN<10>
J 0
(-5490 2735);
DISPLAY 0.659574 (-5490 2735);
PAINT MONO (-5490 2735);
DISPLAY INVISIBLE (-5490 2735);
FORCEPROP 1 LASTPIN (-5500 2725) BN 10
J 2
(-5488 2733);
DISPLAY 0.617021 (-5488 2733);
PAINT GREEN (-5488 2733);
FORCEPROP 2 LAST CDS_LIB mstr_standard
J 0
(-5550 2725);
PAINT MONO (-5550 2725);
DISPLAY INVISIBLE (-5550 2725);
FORCEPROP 1 LAST BODY_TYPE PLUMBING
J 2
(-5550 2775);
DISPLAY 1.446809 (-5550 2775);
PAINT GREEN (-5550 2775);
DISPLAY INVISIBLE (-5550 2775);
FORCEPROP 1 LAST HDL_TAP TRUE
J 2
(-5875 2600);
DISPLAY 1.446809 (-5875 2600);
PAINT GREEN (-5875 2600);
DISPLAY INVISIBLE (-5875 2600);
FORCEPROP 1 LAST PATH I28
J 2
(-5548 2725);
DISPLAY 0.872340 (-5548 2725);
PAINT GREEN (-5548 2725);
DISPLAY INVISIBLE (-5548 2725);
FORCEADD TAP..1
R 2
(-5550 2775);
FORCEPROP 3 LASTPIN (-5500 2775) SIG_NAME P3E_CPU1_PE3_MP_RXN<11>
J 0
(-5490 2785);
DISPLAY 0.659574 (-5490 2785);
PAINT MONO (-5490 2785);
DISPLAY INVISIBLE (-5490 2785);
FORCEPROP 1 LASTPIN (-5500 2775) BN 11
J 2
(-5488 2783);
DISPLAY 0.617021 (-5488 2783);
PAINT GREEN (-5488 2783);
FORCEPROP 2 LAST CDS_LIB mstr_standard
J 0
(-5550 2775);
PAINT MONO (-5550 2775);
DISPLAY INVISIBLE (-5550 2775);
FORCEPROP 1 LAST BODY_TYPE PLUMBING
J 2
(-5550 2825);
DISPLAY 1.446809 (-5550 2825);
PAINT GREEN (-5550 2825);
DISPLAY INVISIBLE (-5550 2825);
FORCEPROP 1 LAST HDL_TAP TRUE
J 2
(-5875 2650);
DISPLAY 1.446809 (-5875 2650);
PAINT GREEN (-5875 2650);
DISPLAY INVISIBLE (-5875 2650);
FORCEPROP 1 LAST PATH I29
J 2
(-5548 2775);
DISPLAY 0.872340 (-5548 2775);
PAINT GREEN (-5548 2775);
DISPLAY INVISIBLE (-5548 2775);
FORCEADD TAP..1
R 2
(-5400 2875);
FORCEPROP 3 LASTPIN (-5350 2875) SIG_NAME P3E_CPU1_PE3_MP_RXP<8>
J 0
(-5340 2885);
DISPLAY 0.659574 (-5340 2885);
PAINT MONO (-5340 2885);
DISPLAY INVISIBLE (-5340 2885);
FORCEPROP 1 LASTPIN (-5350 2875) BN 8
J 2
(-5338 2883);
DISPLAY 0.617021 (-5338 2883);
PAINT GREEN (-5338 2883);
FORCEPROP 2 LAST CDS_LIB mstr_standard
J 0
(-5400 2875);
PAINT MONO (-5400 2875);
DISPLAY INVISIBLE (-5400 2875);
FORCEPROP 1 LAST BODY_TYPE PLUMBING
J 2
(-5400 2925);
DISPLAY 1.446809 (-5400 2925);
PAINT GREEN (-5400 2925);
DISPLAY INVISIBLE (-5400 2925);
FORCEPROP 1 LAST HDL_TAP TRUE
J 2
(-5725 2750);
DISPLAY 1.446809 (-5725 2750);
PAINT GREEN (-5725 2750);
DISPLAY INVISIBLE (-5725 2750);
FORCEPROP 1 LAST PATH I30
J 2
(-5398 2875);
DISPLAY 0.872340 (-5398 2875);
PAINT GREEN (-5398 2875);
DISPLAY INVISIBLE (-5398 2875);
FORCEADD TAP..1
R 2
(-5400 2925);
FORCEPROP 3 LASTPIN (-5350 2925) SIG_NAME P3E_CPU1_PE3_MP_RXP<9>
J 0
(-5340 2935);
DISPLAY 0.659574 (-5340 2935);
PAINT MONO (-5340 2935);
DISPLAY INVISIBLE (-5340 2935);
FORCEPROP 1 LASTPIN (-5350 2925) BN 9
J 2
(-5338 2933);
DISPLAY 0.617021 (-5338 2933);
PAINT GREEN (-5338 2933);
FORCEPROP 2 LAST CDS_LIB mstr_standard
J 0
(-5400 2925);
PAINT MONO (-5400 2925);
DISPLAY INVISIBLE (-5400 2925);
FORCEPROP 1 LAST BODY_TYPE PLUMBING
J 2
(-5400 2975);
DISPLAY 1.446809 (-5400 2975);
PAINT GREEN (-5400 2975);
DISPLAY INVISIBLE (-5400 2975);
FORCEPROP 1 LAST HDL_TAP TRUE
J 2
(-5725 2800);
DISPLAY 1.446809 (-5725 2800);
PAINT GREEN (-5725 2800);
DISPLAY INVISIBLE (-5725 2800);
FORCEPROP 1 LAST PATH I31
J 2
(-5398 2925);
DISPLAY 0.872340 (-5398 2925);
PAINT GREEN (-5398 2925);
DISPLAY INVISIBLE (-5398 2925);
FORCEADD TAP..1
R 2
(-5400 2975);
FORCEPROP 3 LASTPIN (-5350 2975) SIG_NAME P3E_CPU1_PE3_MP_RXP<10>
J 0
(-5340 2985);
DISPLAY 0.659574 (-5340 2985);
PAINT MONO (-5340 2985);
DISPLAY INVISIBLE (-5340 2985);
FORCEPROP 1 LASTPIN (-5350 2975) BN 10
J 2
(-5338 2983);
DISPLAY 0.617021 (-5338 2983);
PAINT GREEN (-5338 2983);
FORCEPROP 2 LAST CDS_LIB mstr_standard
J 0
(-5400 2975);
PAINT MONO (-5400 2975);
DISPLAY INVISIBLE (-5400 2975);
FORCEPROP 1 LAST BODY_TYPE PLUMBING
J 2
(-5400 3025);
DISPLAY 1.446809 (-5400 3025);
PAINT GREEN (-5400 3025);
DISPLAY INVISIBLE (-5400 3025);
FORCEPROP 1 LAST HDL_TAP TRUE
J 2
(-5725 2850);
DISPLAY 1.446809 (-5725 2850);
PAINT GREEN (-5725 2850);
DISPLAY INVISIBLE (-5725 2850);
FORCEPROP 1 LAST PATH I32
J 2
(-5398 2975);
DISPLAY 0.872340 (-5398 2975);
PAINT GREEN (-5398 2975);
DISPLAY INVISIBLE (-5398 2975);
FORCEADD TAP..1
R 2
(-5400 3025);
FORCEPROP 3 LASTPIN (-5350 3025) SIG_NAME P3E_CPU1_PE3_MP_RXP<11>
J 0
(-5340 3035);
DISPLAY 0.659574 (-5340 3035);
PAINT MONO (-5340 3035);
DISPLAY INVISIBLE (-5340 3035);
FORCEPROP 1 LASTPIN (-5350 3025) BN 11
J 2
(-5338 3033);
DISPLAY 0.617021 (-5338 3033);
PAINT GREEN (-5338 3033);
FORCEPROP 2 LAST CDS_LIB mstr_standard
J 0
(-5400 3025);
PAINT MONO (-5400 3025);
DISPLAY INVISIBLE (-5400 3025);
FORCEPROP 1 LAST BODY_TYPE PLUMBING
J 2
(-5400 3075);
DISPLAY 1.446809 (-5400 3075);
PAINT GREEN (-5400 3075);
DISPLAY INVISIBLE (-5400 3075);
FORCEPROP 1 LAST HDL_TAP TRUE
J 2
(-5725 2900);
DISPLAY 1.446809 (-5725 2900);
PAINT GREEN (-5725 2900);
DISPLAY INVISIBLE (-5725 2900);
FORCEPROP 1 LAST PATH I33
J 2
(-5398 3025);
DISPLAY 0.872340 (-5398 3025);
PAINT GREEN (-5398 3025);
DISPLAY INVISIBLE (-5398 3025);
FORCEADD TAP..1
R 2
(-5550 3175);
FORCEPROP 3 LASTPIN (-5500 3175) SIG_NAME P3E_CPU1_PE3_MP_RXN<13>
J 0
(-5490 3185);
DISPLAY 0.659574 (-5490 3185);
PAINT MONO (-5490 3185);
DISPLAY INVISIBLE (-5490 3185);
FORCEPROP 1 LASTPIN (-5500 3175) BN 13
J 2
(-5488 3183);
DISPLAY 0.617021 (-5488 3183);
PAINT GREEN (-5488 3183);
FORCEPROP 2 LAST CDS_LIB mstr_standard
J 0
(-5550 3175);
PAINT MONO (-5550 3175);
DISPLAY INVISIBLE (-5550 3175);
FORCEPROP 1 LAST BODY_TYPE PLUMBING
J 2
(-5550 3225);
DISPLAY 1.446809 (-5550 3225);
PAINT GREEN (-5550 3225);
DISPLAY INVISIBLE (-5550 3225);
FORCEPROP 1 LAST HDL_TAP TRUE
J 2
(-5875 3050);
DISPLAY 1.446809 (-5875 3050);
PAINT GREEN (-5875 3050);
DISPLAY INVISIBLE (-5875 3050);
FORCEPROP 1 LAST PATH I34
J 2
(-5548 3175);
DISPLAY 0.872340 (-5548 3175);
PAINT GREEN (-5548 3175);
DISPLAY INVISIBLE (-5548 3175);
FORCEADD TAP..1
R 2
(-5550 3375);
FORCEPROP 3 LASTPIN (-5500 3375) SIG_NAME P3E_CPU1_PE3_MP_RXN<12>
J 0
(-5490 3385);
DISPLAY 0.659574 (-5490 3385);
PAINT MONO (-5490 3385);
DISPLAY INVISIBLE (-5490 3385);
FORCEPROP 1 LASTPIN (-5500 3375) BN 12
J 2
(-5488 3383);
DISPLAY 0.617021 (-5488 3383);
PAINT GREEN (-5488 3383);
FORCEPROP 2 LAST CDS_LIB mstr_standard
J 0
(-5550 3375);
PAINT MONO (-5550 3375);
DISPLAY INVISIBLE (-5550 3375);
FORCEPROP 1 LAST BODY_TYPE PLUMBING
J 2
(-5550 3425);
DISPLAY 1.446809 (-5550 3425);
PAINT GREEN (-5550 3425);
DISPLAY INVISIBLE (-5550 3425);
FORCEPROP 1 LAST HDL_TAP TRUE
J 2
(-5875 3250);
DISPLAY 1.446809 (-5875 3250);
PAINT GREEN (-5875 3250);
DISPLAY INVISIBLE (-5875 3250);
FORCEPROP 1 LAST PATH I35
J 2
(-5548 3375);
DISPLAY 0.872340 (-5548 3375);
PAINT GREEN (-5548 3375);
DISPLAY INVISIBLE (-5548 3375);
FORCEADD TAP..1
R 2
(-5550 3225);
FORCEPROP 3 LASTPIN (-5500 3225) SIG_NAME P3E_CPU1_PE3_MP_RXN<14>
J 0
(-5490 3235);
DISPLAY 0.659574 (-5490 3235);
PAINT MONO (-5490 3235);
DISPLAY INVISIBLE (-5490 3235);
FORCEPROP 1 LASTPIN (-5500 3225) BN 14
J 2
(-5488 3233);
DISPLAY 0.617021 (-5488 3233);
PAINT GREEN (-5488 3233);
FORCEPROP 2 LAST CDS_LIB mstr_standard
J 0
(-5550 3225);
PAINT MONO (-5550 3225);
DISPLAY INVISIBLE (-5550 3225);
FORCEPROP 1 LAST BODY_TYPE PLUMBING
J 2
(-5550 3275);
DISPLAY 1.446809 (-5550 3275);
PAINT GREEN (-5550 3275);
DISPLAY INVISIBLE (-5550 3275);
FORCEPROP 1 LAST HDL_TAP TRUE
J 2
(-5875 3100);
DISPLAY 1.446809 (-5875 3100);
PAINT GREEN (-5875 3100);
DISPLAY INVISIBLE (-5875 3100);
FORCEPROP 1 LAST PATH I36
J 2
(-5548 3225);
DISPLAY 0.872340 (-5548 3225);
PAINT GREEN (-5548 3225);
DISPLAY INVISIBLE (-5548 3225);
FORCEADD TAP..1
R 2
(-5550 3275);
FORCEPROP 3 LASTPIN (-5500 3275) SIG_NAME P3E_CPU1_PE3_MP_RXN<15>
J 0
(-5490 3285);
DISPLAY 0.659574 (-5490 3285);
PAINT MONO (-5490 3285);
DISPLAY INVISIBLE (-5490 3285);
FORCEPROP 1 LASTPIN (-5500 3275) BN 15
J 2
(-5488 3283);
DISPLAY 0.617021 (-5488 3283);
PAINT GREEN (-5488 3283);
FORCEPROP 2 LAST CDS_LIB mstr_standard
J 0
(-5550 3275);
PAINT MONO (-5550 3275);
DISPLAY INVISIBLE (-5550 3275);
FORCEPROP 1 LAST BODY_TYPE PLUMBING
J 2
(-5550 3325);
DISPLAY 1.446809 (-5550 3325);
PAINT GREEN (-5550 3325);
DISPLAY INVISIBLE (-5550 3325);
FORCEPROP 1 LAST HDL_TAP TRUE
J 2
(-5875 3150);
DISPLAY 1.446809 (-5875 3150);
PAINT GREEN (-5875 3150);
DISPLAY INVISIBLE (-5875 3150);
FORCEPROP 1 LAST PATH I37
J 2
(-5548 3275);
DISPLAY 0.872340 (-5548 3275);
PAINT GREEN (-5548 3275);
DISPLAY INVISIBLE (-5548 3275);
FORCEADD TAP..1
R 2
(-5400 3125);
FORCEPROP 3 LASTPIN (-5350 3125) SIG_NAME P3E_CPU1_PE3_MP_RXP<12>
J 0
(-5340 3135);
DISPLAY 0.659574 (-5340 3135);
PAINT MONO (-5340 3135);
DISPLAY INVISIBLE (-5340 3135);
FORCEPROP 1 LASTPIN (-5350 3125) BN 12
J 2
(-5338 3133);
DISPLAY 0.617021 (-5338 3133);
PAINT GREEN (-5338 3133);
FORCEPROP 2 LAST CDS_LIB mstr_standard
J 0
(-5400 3125);
PAINT MONO (-5400 3125);
DISPLAY INVISIBLE (-5400 3125);
FORCEPROP 1 LAST BODY_TYPE PLUMBING
J 2
(-5400 3175);
DISPLAY 1.446809 (-5400 3175);
PAINT GREEN (-5400 3175);
DISPLAY INVISIBLE (-5400 3175);
FORCEPROP 1 LAST HDL_TAP TRUE
J 2
(-5725 3000);
DISPLAY 1.446809 (-5725 3000);
PAINT GREEN (-5725 3000);
DISPLAY INVISIBLE (-5725 3000);
FORCEPROP 1 LAST PATH I38
J 2
(-5398 3125);
DISPLAY 0.872340 (-5398 3125);
PAINT GREEN (-5398 3125);
DISPLAY INVISIBLE (-5398 3125);
FORCEADD TAP..1
R 2
(-5400 3425);
FORCEPROP 3 LASTPIN (-5350 3425) SIG_NAME P3E_CPU1_PE3_MP_RXP<13>
J 0
(-5340 3435);
DISPLAY 0.659574 (-5340 3435);
PAINT MONO (-5340 3435);
DISPLAY INVISIBLE (-5340 3435);
FORCEPROP 1 LASTPIN (-5350 3425) BN 13
J 2
(-5338 3433);
DISPLAY 0.617021 (-5338 3433);
PAINT GREEN (-5338 3433);
FORCEPROP 2 LAST CDS_LIB mstr_standard
J 0
(-5400 3425);
PAINT MONO (-5400 3425);
DISPLAY INVISIBLE (-5400 3425);
FORCEPROP 1 LAST BODY_TYPE PLUMBING
J 2
(-5400 3475);
DISPLAY 1.446809 (-5400 3475);
PAINT GREEN (-5400 3475);
DISPLAY INVISIBLE (-5400 3475);
FORCEPROP 1 LAST HDL_TAP TRUE
J 2
(-5725 3300);
DISPLAY 1.446809 (-5725 3300);
PAINT GREEN (-5725 3300);
DISPLAY INVISIBLE (-5725 3300);
FORCEPROP 1 LAST PATH I39
J 2
(-5398 3425);
DISPLAY 0.872340 (-5398 3425);
PAINT GREEN (-5398 3425);
DISPLAY INVISIBLE (-5398 3425);
FORCEADD TAP..1
R 2
(-5400 3525);
FORCEPROP 3 LASTPIN (-5350 3525) SIG_NAME P3E_CPU1_PE3_MP_RXP<15>
J 0
(-5340 3535);
DISPLAY 0.659574 (-5340 3535);
PAINT MONO (-5340 3535);
DISPLAY INVISIBLE (-5340 3535);
FORCEPROP 1 LASTPIN (-5350 3525) BN 15
J 2
(-5338 3533);
DISPLAY 0.617021 (-5338 3533);
PAINT GREEN (-5338 3533);
FORCEPROP 2 LAST CDS_LIB mstr_standard
J 0
(-5400 3525);
PAINT MONO (-5400 3525);
DISPLAY INVISIBLE (-5400 3525);
FORCEPROP 1 LAST BODY_TYPE PLUMBING
J 2
(-5400 3575);
DISPLAY 1.446809 (-5400 3575);
PAINT GREEN (-5400 3575);
DISPLAY INVISIBLE (-5400 3575);
FORCEPROP 1 LAST HDL_TAP TRUE
J 2
(-5725 3400);
DISPLAY 1.446809 (-5725 3400);
PAINT GREEN (-5725 3400);
DISPLAY INVISIBLE (-5725 3400);
FORCEPROP 1 LAST PATH I40
J 2
(-5398 3525);
DISPLAY 0.872340 (-5398 3525);
PAINT GREEN (-5398 3525);
DISPLAY INVISIBLE (-5398 3525);
FORCEADD TAP..1
R 2
(-5400 3475);
FORCEPROP 3 LASTPIN (-5350 3475) SIG_NAME P3E_CPU1_PE3_MP_RXP<14>
J 0
(-5340 3485);
DISPLAY 0.659574 (-5340 3485);
PAINT MONO (-5340 3485);
DISPLAY INVISIBLE (-5340 3485);
FORCEPROP 1 LASTPIN (-5350 3475) BN 14
J 2
(-5338 3483);
DISPLAY 0.617021 (-5338 3483);
PAINT GREEN (-5338 3483);
FORCEPROP 2 LAST CDS_LIB mstr_standard
J 0
(-5400 3475);
PAINT MONO (-5400 3475);
DISPLAY INVISIBLE (-5400 3475);
FORCEPROP 1 LAST BODY_TYPE PLUMBING
J 2
(-5400 3525);
DISPLAY 1.446809 (-5400 3525);
PAINT GREEN (-5400 3525);
DISPLAY INVISIBLE (-5400 3525);
FORCEPROP 1 LAST HDL_TAP TRUE
J 2
(-5725 3350);
DISPLAY 1.446809 (-5725 3350);
PAINT GREEN (-5725 3350);
DISPLAY INVISIBLE (-5725 3350);
FORCEPROP 1 LAST PATH I41
J 2
(-5398 3475);
DISPLAY 0.872340 (-5398 3475);
PAINT GREEN (-5398 3475);
DISPLAY INVISIBLE (-5398 3475);
FORCEADD TAP..1
(-2775 1675);
FORCEPROP 3 LASTPIN (-2825 1675) SIG_NAME P3E_CPU1_PE3_MP_TXN<1>
J 0
(-2815 1685);
DISPLAY 0.659574 (-2815 1685);
PAINT MONO (-2815 1685);
DISPLAY INVISIBLE (-2815 1685);
FORCEPROP 1 LASTPIN (-2825 1675) BN 1
J 0
(-2837 1683);
DISPLAY 0.617021 (-2837 1683);
PAINT GREEN (-2837 1683);
FORCEPROP 2 LAST CDS_LIB mstr_standard
J 2
(-2775 1675);
PAINT MONO (-2775 1675);
DISPLAY INVISIBLE (-2775 1675);
FORCEPROP 1 LAST BODY_TYPE PLUMBING
J 0
(-2775 1725);
DISPLAY 1.446809 (-2775 1725);
PAINT GREEN (-2775 1725);
DISPLAY INVISIBLE (-2775 1725);
FORCEPROP 1 LAST HDL_TAP TRUE
J 0
(-2450 1550);
DISPLAY 1.446809 (-2450 1550);
PAINT GREEN (-2450 1550);
DISPLAY INVISIBLE (-2450 1550);
FORCEPROP 1 LAST PATH I42
J 0
(-2777 1675);
DISPLAY 0.872340 (-2777 1675);
PAINT GREEN (-2777 1675);
DISPLAY INVISIBLE (-2777 1675);
FORCEADD TAP..1
(-2775 1625);
FORCEPROP 3 LASTPIN (-2825 1625) SIG_NAME P3E_CPU1_PE3_MP_TXN<0>
J 0
(-2815 1635);
DISPLAY 0.659574 (-2815 1635);
PAINT MONO (-2815 1635);
DISPLAY INVISIBLE (-2815 1635);
FORCEPROP 1 LASTPIN (-2825 1625) BN 0
J 0
(-2837 1633);
DISPLAY 0.617021 (-2837 1633);
PAINT GREEN (-2837 1633);
FORCEPROP 2 LAST CDS_LIB mstr_standard
J 2
(-2775 1625);
PAINT MONO (-2775 1625);
DISPLAY INVISIBLE (-2775 1625);
FORCEPROP 1 LAST BODY_TYPE PLUMBING
J 0
(-2775 1675);
DISPLAY 1.446809 (-2775 1675);
PAINT GREEN (-2775 1675);
DISPLAY INVISIBLE (-2775 1675);
FORCEPROP 1 LAST HDL_TAP TRUE
J 0
(-2450 1500);
DISPLAY 1.446809 (-2450 1500);
PAINT GREEN (-2450 1500);
DISPLAY INVISIBLE (-2450 1500);
FORCEPROP 1 LAST PATH I43
J 0
(-2777 1625);
DISPLAY 0.872340 (-2777 1625);
PAINT GREEN (-2777 1625);
DISPLAY INVISIBLE (-2777 1625);
FORCEADD TAP..1
(-2775 1725);
FORCEPROP 3 LASTPIN (-2825 1725) SIG_NAME P3E_CPU1_PE3_MP_TXN<2>
J 0
(-2815 1735);
DISPLAY 0.659574 (-2815 1735);
PAINT MONO (-2815 1735);
DISPLAY INVISIBLE (-2815 1735);
FORCEPROP 1 LASTPIN (-2825 1725) BN 2
J 0
(-2837 1733);
DISPLAY 0.617021 (-2837 1733);
PAINT GREEN (-2837 1733);
FORCEPROP 2 LAST CDS_LIB mstr_standard
J 2
(-2775 1725);
PAINT MONO (-2775 1725);
DISPLAY INVISIBLE (-2775 1725);
FORCEPROP 1 LAST BODY_TYPE PLUMBING
J 0
(-2775 1775);
DISPLAY 1.446809 (-2775 1775);
PAINT GREEN (-2775 1775);
DISPLAY INVISIBLE (-2775 1775);
FORCEPROP 1 LAST HDL_TAP TRUE
J 0
(-2450 1600);
DISPLAY 1.446809 (-2450 1600);
PAINT GREEN (-2450 1600);
DISPLAY INVISIBLE (-2450 1600);
FORCEPROP 1 LAST PATH I44
J 0
(-2777 1725);
DISPLAY 0.872340 (-2777 1725);
PAINT GREEN (-2777 1725);
DISPLAY INVISIBLE (-2777 1725);
FORCEADD TAP..1
(-2775 1775);
FORCEPROP 3 LASTPIN (-2825 1775) SIG_NAME P3E_CPU1_PE3_MP_TXN<3>
J 0
(-2815 1785);
DISPLAY 0.659574 (-2815 1785);
PAINT MONO (-2815 1785);
DISPLAY INVISIBLE (-2815 1785);
FORCEPROP 1 LASTPIN (-2825 1775) BN 3
J 0
(-2837 1783);
DISPLAY 0.617021 (-2837 1783);
PAINT GREEN (-2837 1783);
FORCEPROP 2 LAST CDS_LIB mstr_standard
J 2
(-2775 1775);
PAINT MONO (-2775 1775);
DISPLAY INVISIBLE (-2775 1775);
FORCEPROP 1 LAST BODY_TYPE PLUMBING
J 0
(-2775 1825);
DISPLAY 1.446809 (-2775 1825);
PAINT GREEN (-2775 1825);
DISPLAY INVISIBLE (-2775 1825);
FORCEPROP 1 LAST HDL_TAP TRUE
J 0
(-2450 1650);
DISPLAY 1.446809 (-2450 1650);
PAINT GREEN (-2450 1650);
DISPLAY INVISIBLE (-2450 1650);
FORCEPROP 1 LAST PATH I45
J 0
(-2777 1775);
DISPLAY 0.872340 (-2777 1775);
PAINT GREEN (-2777 1775);
DISPLAY INVISIBLE (-2777 1775);
FORCEADD TAP..1
(-2925 1875);
FORCEPROP 3 LASTPIN (-2975 1875) SIG_NAME P3E_CPU1_PE3_MP_TXP<0>
J 0
(-2965 1885);
DISPLAY 0.659574 (-2965 1885);
PAINT MONO (-2965 1885);
DISPLAY INVISIBLE (-2965 1885);
FORCEPROP 1 LASTPIN (-2975 1875) BN 0
J 0
(-2987 1883);
DISPLAY 0.617021 (-2987 1883);
PAINT GREEN (-2987 1883);
FORCEPROP 2 LAST CDS_LIB mstr_standard
J 2
(-2925 1875);
PAINT MONO (-2925 1875);
DISPLAY INVISIBLE (-2925 1875);
FORCEPROP 1 LAST BODY_TYPE PLUMBING
J 0
(-2925 1925);
DISPLAY 1.446809 (-2925 1925);
PAINT GREEN (-2925 1925);
DISPLAY INVISIBLE (-2925 1925);
FORCEPROP 1 LAST HDL_TAP TRUE
J 0
(-2600 1750);
DISPLAY 1.446809 (-2600 1750);
PAINT GREEN (-2600 1750);
DISPLAY INVISIBLE (-2600 1750);
FORCEPROP 1 LAST PATH I46
J 0
(-2927 1875);
DISPLAY 0.872340 (-2927 1875);
PAINT GREEN (-2927 1875);
DISPLAY INVISIBLE (-2927 1875);
FORCEADD TAP..1
(-2925 1975);
FORCEPROP 3 LASTPIN (-2975 1975) SIG_NAME P3E_CPU1_PE3_MP_TXP<2>
J 0
(-2965 1985);
DISPLAY 0.659574 (-2965 1985);
PAINT MONO (-2965 1985);
DISPLAY INVISIBLE (-2965 1985);
FORCEPROP 1 LASTPIN (-2975 1975) BN 2
J 0
(-2987 1983);
DISPLAY 0.617021 (-2987 1983);
PAINT GREEN (-2987 1983);
FORCEPROP 2 LAST CDS_LIB mstr_standard
J 2
(-2925 1975);
PAINT MONO (-2925 1975);
DISPLAY INVISIBLE (-2925 1975);
FORCEPROP 1 LAST BODY_TYPE PLUMBING
J 0
(-2925 2025);
DISPLAY 1.446809 (-2925 2025);
PAINT GREEN (-2925 2025);
DISPLAY INVISIBLE (-2925 2025);
FORCEPROP 1 LAST HDL_TAP TRUE
J 0
(-2600 1850);
DISPLAY 1.446809 (-2600 1850);
PAINT GREEN (-2600 1850);
DISPLAY INVISIBLE (-2600 1850);
FORCEPROP 1 LAST PATH I47
J 0
(-2927 1975);
DISPLAY 0.872340 (-2927 1975);
PAINT GREEN (-2927 1975);
DISPLAY INVISIBLE (-2927 1975);
FORCEADD TAP..1
(-2925 1925);
FORCEPROP 3 LASTPIN (-2975 1925) SIG_NAME P3E_CPU1_PE3_MP_TXP<1>
J 0
(-2965 1935);
DISPLAY 0.659574 (-2965 1935);
PAINT MONO (-2965 1935);
DISPLAY INVISIBLE (-2965 1935);
FORCEPROP 1 LASTPIN (-2975 1925) BN 1
J 0
(-2987 1933);
DISPLAY 0.617021 (-2987 1933);
PAINT GREEN (-2987 1933);
FORCEPROP 2 LAST CDS_LIB mstr_standard
J 2
(-2925 1925);
PAINT MONO (-2925 1925);
DISPLAY INVISIBLE (-2925 1925);
FORCEPROP 1 LAST BODY_TYPE PLUMBING
J 0
(-2925 1975);
DISPLAY 1.446809 (-2925 1975);
PAINT GREEN (-2925 1975);
DISPLAY INVISIBLE (-2925 1975);
FORCEPROP 1 LAST HDL_TAP TRUE
J 0
(-2600 1800);
DISPLAY 1.446809 (-2600 1800);
PAINT GREEN (-2600 1800);
DISPLAY INVISIBLE (-2600 1800);
FORCEPROP 1 LAST PATH I48
J 0
(-2927 1925);
DISPLAY 0.872340 (-2927 1925);
PAINT GREEN (-2927 1925);
DISPLAY INVISIBLE (-2927 1925);
FORCEADD TAP..1
(-2925 2025);
FORCEPROP 3 LASTPIN (-2975 2025) SIG_NAME P3E_CPU1_PE3_MP_TXP<3>
J 0
(-2965 2035);
DISPLAY 0.659574 (-2965 2035);
PAINT MONO (-2965 2035);
DISPLAY INVISIBLE (-2965 2035);
FORCEPROP 1 LASTPIN (-2975 2025) BN 3
J 0
(-2987 2033);
DISPLAY 0.617021 (-2987 2033);
PAINT GREEN (-2987 2033);
FORCEPROP 2 LAST CDS_LIB mstr_standard
J 2
(-2925 2025);
PAINT MONO (-2925 2025);
DISPLAY INVISIBLE (-2925 2025);
FORCEPROP 1 LAST BODY_TYPE PLUMBING
J 0
(-2925 2075);
DISPLAY 1.446809 (-2925 2075);
PAINT GREEN (-2925 2075);
DISPLAY INVISIBLE (-2925 2075);
FORCEPROP 1 LAST HDL_TAP TRUE
J 0
(-2600 1900);
DISPLAY 1.446809 (-2600 1900);
PAINT GREEN (-2600 1900);
DISPLAY INVISIBLE (-2600 1900);
FORCEPROP 1 LAST PATH I49
J 0
(-2927 2025);
DISPLAY 0.872340 (-2927 2025);
PAINT GREEN (-2927 2025);
DISPLAY INVISIBLE (-2927 2025);
FORCEADD TAP..1
(-2775 2125);
FORCEPROP 3 LASTPIN (-2825 2125) SIG_NAME P3E_CPU1_PE3_MP_TXN<4>
J 0
(-2815 2135);
DISPLAY 0.659574 (-2815 2135);
PAINT MONO (-2815 2135);
DISPLAY INVISIBLE (-2815 2135);
FORCEPROP 1 LASTPIN (-2825 2125) BN 4
J 0
(-2837 2133);
DISPLAY 0.617021 (-2837 2133);
PAINT GREEN (-2837 2133);
FORCEPROP 2 LAST CDS_LIB mstr_standard
J 2
(-2775 2125);
PAINT MONO (-2775 2125);
DISPLAY INVISIBLE (-2775 2125);
FORCEPROP 1 LAST BODY_TYPE PLUMBING
J 0
(-2775 2175);
DISPLAY 1.446809 (-2775 2175);
PAINT GREEN (-2775 2175);
DISPLAY INVISIBLE (-2775 2175);
FORCEPROP 1 LAST HDL_TAP TRUE
J 0
(-2450 2000);
DISPLAY 1.446809 (-2450 2000);
PAINT GREEN (-2450 2000);
DISPLAY INVISIBLE (-2450 2000);
FORCEPROP 1 LAST PATH I50
J 0
(-2777 2125);
DISPLAY 0.872340 (-2777 2125);
PAINT GREEN (-2777 2125);
DISPLAY INVISIBLE (-2777 2125);
FORCEADD TAP..1
(-2775 2175);
FORCEPROP 3 LASTPIN (-2825 2175) SIG_NAME P3E_CPU1_PE3_MP_TXN<5>
J 0
(-2815 2185);
DISPLAY 0.659574 (-2815 2185);
PAINT MONO (-2815 2185);
DISPLAY INVISIBLE (-2815 2185);
FORCEPROP 1 LASTPIN (-2825 2175) BN 5
J 0
(-2837 2183);
DISPLAY 0.617021 (-2837 2183);
PAINT GREEN (-2837 2183);
FORCEPROP 2 LAST CDS_LIB mstr_standard
J 2
(-2775 2175);
PAINT MONO (-2775 2175);
DISPLAY INVISIBLE (-2775 2175);
FORCEPROP 1 LAST BODY_TYPE PLUMBING
J 0
(-2775 2225);
DISPLAY 1.446809 (-2775 2225);
PAINT GREEN (-2775 2225);
DISPLAY INVISIBLE (-2775 2225);
FORCEPROP 1 LAST HDL_TAP TRUE
J 0
(-2450 2050);
DISPLAY 1.446809 (-2450 2050);
PAINT GREEN (-2450 2050);
DISPLAY INVISIBLE (-2450 2050);
FORCEPROP 1 LAST PATH I51
J 0
(-2777 2175);
DISPLAY 0.872340 (-2777 2175);
PAINT GREEN (-2777 2175);
DISPLAY INVISIBLE (-2777 2175);
FORCEADD TAP..1
(-2775 2225);
FORCEPROP 3 LASTPIN (-2825 2225) SIG_NAME P3E_CPU1_PE3_MP_TXN<6>
J 0
(-2815 2235);
DISPLAY 0.659574 (-2815 2235);
PAINT MONO (-2815 2235);
DISPLAY INVISIBLE (-2815 2235);
FORCEPROP 1 LASTPIN (-2825 2225) BN 6
J 0
(-2837 2233);
DISPLAY 0.617021 (-2837 2233);
PAINT GREEN (-2837 2233);
FORCEPROP 2 LAST CDS_LIB mstr_standard
J 2
(-2775 2225);
PAINT MONO (-2775 2225);
DISPLAY INVISIBLE (-2775 2225);
FORCEPROP 1 LAST BODY_TYPE PLUMBING
J 0
(-2775 2275);
DISPLAY 1.446809 (-2775 2275);
PAINT GREEN (-2775 2275);
DISPLAY INVISIBLE (-2775 2275);
FORCEPROP 1 LAST HDL_TAP TRUE
J 0
(-2450 2100);
DISPLAY 1.446809 (-2450 2100);
PAINT GREEN (-2450 2100);
DISPLAY INVISIBLE (-2450 2100);
FORCEPROP 1 LAST PATH I52
J 0
(-2777 2225);
DISPLAY 0.872340 (-2777 2225);
PAINT GREEN (-2777 2225);
DISPLAY INVISIBLE (-2777 2225);
FORCEADD TAP..1
(-2775 2275);
FORCEPROP 3 LASTPIN (-2825 2275) SIG_NAME P3E_CPU1_PE3_MP_TXN<7>
J 0
(-2815 2285);
DISPLAY 0.659574 (-2815 2285);
PAINT MONO (-2815 2285);
DISPLAY INVISIBLE (-2815 2285);
FORCEPROP 1 LASTPIN (-2825 2275) BN 7
J 0
(-2837 2283);
DISPLAY 0.617021 (-2837 2283);
PAINT GREEN (-2837 2283);
FORCEPROP 2 LAST CDS_LIB mstr_standard
J 2
(-2775 2275);
PAINT MONO (-2775 2275);
DISPLAY INVISIBLE (-2775 2275);
FORCEPROP 1 LAST BODY_TYPE PLUMBING
J 0
(-2775 2325);
DISPLAY 1.446809 (-2775 2325);
PAINT GREEN (-2775 2325);
DISPLAY INVISIBLE (-2775 2325);
FORCEPROP 1 LAST HDL_TAP TRUE
J 0
(-2450 2150);
DISPLAY 1.446809 (-2450 2150);
PAINT GREEN (-2450 2150);
DISPLAY INVISIBLE (-2450 2150);
FORCEPROP 1 LAST PATH I53
J 0
(-2777 2275);
DISPLAY 0.872340 (-2777 2275);
PAINT GREEN (-2777 2275);
DISPLAY INVISIBLE (-2777 2275);
FORCEADD TAP..1
(-2925 2425);
FORCEPROP 3 LASTPIN (-2975 2425) SIG_NAME P3E_CPU1_PE3_MP_TXP<5>
J 0
(-2965 2435);
DISPLAY 0.659574 (-2965 2435);
PAINT MONO (-2965 2435);
DISPLAY INVISIBLE (-2965 2435);
FORCEPROP 1 LASTPIN (-2975 2425) BN 5
J 0
(-2987 2433);
DISPLAY 0.617021 (-2987 2433);
PAINT GREEN (-2987 2433);
FORCEPROP 2 LAST CDS_LIB mstr_standard
J 2
(-2925 2425);
PAINT MONO (-2925 2425);
DISPLAY INVISIBLE (-2925 2425);
FORCEPROP 1 LAST BODY_TYPE PLUMBING
J 0
(-2925 2475);
DISPLAY 1.446809 (-2925 2475);
PAINT GREEN (-2925 2475);
DISPLAY INVISIBLE (-2925 2475);
FORCEPROP 1 LAST HDL_TAP TRUE
J 0
(-2600 2300);
DISPLAY 1.446809 (-2600 2300);
PAINT GREEN (-2600 2300);
DISPLAY INVISIBLE (-2600 2300);
FORCEPROP 1 LAST PATH I54
J 0
(-2927 2425);
DISPLAY 0.872340 (-2927 2425);
PAINT GREEN (-2927 2425);
DISPLAY INVISIBLE (-2927 2425);
FORCEADD TAP..1
(-2925 2375);
FORCEPROP 3 LASTPIN (-2975 2375) SIG_NAME P3E_CPU1_PE3_MP_TXP<4>
J 0
(-2965 2385);
DISPLAY 0.659574 (-2965 2385);
PAINT MONO (-2965 2385);
DISPLAY INVISIBLE (-2965 2385);
FORCEPROP 1 LASTPIN (-2975 2375) BN 4
J 0
(-2987 2383);
DISPLAY 0.617021 (-2987 2383);
PAINT GREEN (-2987 2383);
FORCEPROP 2 LAST CDS_LIB mstr_standard
J 2
(-2925 2375);
PAINT MONO (-2925 2375);
DISPLAY INVISIBLE (-2925 2375);
FORCEPROP 1 LAST BODY_TYPE PLUMBING
J 0
(-2925 2425);
DISPLAY 1.446809 (-2925 2425);
PAINT GREEN (-2925 2425);
DISPLAY INVISIBLE (-2925 2425);
FORCEPROP 1 LAST HDL_TAP TRUE
J 0
(-2600 2250);
DISPLAY 1.446809 (-2600 2250);
PAINT GREEN (-2600 2250);
DISPLAY INVISIBLE (-2600 2250);
FORCEPROP 1 LAST PATH I55
J 0
(-2927 2375);
DISPLAY 0.872340 (-2927 2375);
PAINT GREEN (-2927 2375);
DISPLAY INVISIBLE (-2927 2375);
FORCEADD TAP..1
(-2925 2475);
FORCEPROP 3 LASTPIN (-2975 2475) SIG_NAME P3E_CPU1_PE3_MP_TXP<6>
J 0
(-2965 2485);
DISPLAY 0.659574 (-2965 2485);
PAINT MONO (-2965 2485);
DISPLAY INVISIBLE (-2965 2485);
FORCEPROP 1 LASTPIN (-2975 2475) BN 6
J 0
(-2987 2483);
DISPLAY 0.617021 (-2987 2483);
PAINT GREEN (-2987 2483);
FORCEPROP 2 LAST CDS_LIB mstr_standard
J 2
(-2925 2475);
PAINT MONO (-2925 2475);
DISPLAY INVISIBLE (-2925 2475);
FORCEPROP 1 LAST BODY_TYPE PLUMBING
J 0
(-2925 2525);
DISPLAY 1.446809 (-2925 2525);
PAINT GREEN (-2925 2525);
DISPLAY INVISIBLE (-2925 2525);
FORCEPROP 1 LAST HDL_TAP TRUE
J 0
(-2600 2350);
DISPLAY 1.446809 (-2600 2350);
PAINT GREEN (-2600 2350);
DISPLAY INVISIBLE (-2600 2350);
FORCEPROP 1 LAST PATH I56
J 0
(-2927 2475);
DISPLAY 0.872340 (-2927 2475);
PAINT GREEN (-2927 2475);
DISPLAY INVISIBLE (-2927 2475);
FORCEADD TAP..1
(-2925 2525);
FORCEPROP 3 LASTPIN (-2975 2525) SIG_NAME P3E_CPU1_PE3_MP_TXP<7>
J 0
(-2965 2535);
DISPLAY 0.659574 (-2965 2535);
PAINT MONO (-2965 2535);
DISPLAY INVISIBLE (-2965 2535);
FORCEPROP 1 LASTPIN (-2975 2525) BN 7
J 0
(-2987 2533);
DISPLAY 0.617021 (-2987 2533);
PAINT GREEN (-2987 2533);
FORCEPROP 2 LAST CDS_LIB mstr_standard
J 2
(-2925 2525);
PAINT MONO (-2925 2525);
DISPLAY INVISIBLE (-2925 2525);
FORCEPROP 1 LAST BODY_TYPE PLUMBING
J 0
(-2925 2575);
DISPLAY 1.446809 (-2925 2575);
PAINT GREEN (-2925 2575);
DISPLAY INVISIBLE (-2925 2575);
FORCEPROP 1 LAST HDL_TAP TRUE
J 0
(-2600 2400);
DISPLAY 1.446809 (-2600 2400);
PAINT GREEN (-2600 2400);
DISPLAY INVISIBLE (-2600 2400);
FORCEPROP 1 LAST PATH I57
J 0
(-2927 2525);
DISPLAY 0.872340 (-2927 2525);
PAINT GREEN (-2927 2525);
DISPLAY INVISIBLE (-2927 2525);
FORCEADD TAP..1
(-2775 2625);
FORCEPROP 3 LASTPIN (-2825 2625) SIG_NAME P3E_CPU1_PE3_MP_TXN<8>
J 0
(-2815 2635);
DISPLAY 0.659574 (-2815 2635);
PAINT MONO (-2815 2635);
DISPLAY INVISIBLE (-2815 2635);
FORCEPROP 1 LASTPIN (-2825 2625) BN 8
J 0
(-2837 2633);
DISPLAY 0.617021 (-2837 2633);
PAINT GREEN (-2837 2633);
FORCEPROP 2 LAST CDS_LIB mstr_standard
J 2
(-2775 2625);
PAINT MONO (-2775 2625);
DISPLAY INVISIBLE (-2775 2625);
FORCEPROP 1 LAST BODY_TYPE PLUMBING
J 0
(-2775 2675);
DISPLAY 1.446809 (-2775 2675);
PAINT GREEN (-2775 2675);
DISPLAY INVISIBLE (-2775 2675);
FORCEPROP 1 LAST HDL_TAP TRUE
J 0
(-2450 2500);
DISPLAY 1.446809 (-2450 2500);
PAINT GREEN (-2450 2500);
DISPLAY INVISIBLE (-2450 2500);
FORCEPROP 1 LAST PATH I58
J 0
(-2777 2625);
DISPLAY 0.872340 (-2777 2625);
PAINT GREEN (-2777 2625);
DISPLAY INVISIBLE (-2777 2625);
FORCEADD TAP..1
(-2775 2725);
FORCEPROP 3 LASTPIN (-2825 2725) SIG_NAME P3E_CPU1_PE3_MP_TXN<10>
J 0
(-2815 2735);
DISPLAY 0.659574 (-2815 2735);
PAINT MONO (-2815 2735);
DISPLAY INVISIBLE (-2815 2735);
FORCEPROP 1 LASTPIN (-2825 2725) BN 10
J 0
(-2837 2733);
DISPLAY 0.617021 (-2837 2733);
PAINT GREEN (-2837 2733);
FORCEPROP 2 LAST CDS_LIB mstr_standard
J 2
(-2775 2725);
PAINT MONO (-2775 2725);
DISPLAY INVISIBLE (-2775 2725);
FORCEPROP 1 LAST BODY_TYPE PLUMBING
J 0
(-2775 2775);
DISPLAY 1.446809 (-2775 2775);
PAINT GREEN (-2775 2775);
DISPLAY INVISIBLE (-2775 2775);
FORCEPROP 1 LAST HDL_TAP TRUE
J 0
(-2450 2600);
DISPLAY 1.446809 (-2450 2600);
PAINT GREEN (-2450 2600);
DISPLAY INVISIBLE (-2450 2600);
FORCEPROP 1 LAST PATH I59
J 0
(-2777 2725);
DISPLAY 0.872340 (-2777 2725);
PAINT GREEN (-2777 2725);
DISPLAY INVISIBLE (-2777 2725);
FORCEADD TAP..1
(-2775 2675);
FORCEPROP 3 LASTPIN (-2825 2675) SIG_NAME P3E_CPU1_PE3_MP_TXN<9>
J 0
(-2815 2685);
DISPLAY 0.659574 (-2815 2685);
PAINT MONO (-2815 2685);
DISPLAY INVISIBLE (-2815 2685);
FORCEPROP 1 LASTPIN (-2825 2675) BN 9
J 0
(-2837 2683);
DISPLAY 0.617021 (-2837 2683);
PAINT GREEN (-2837 2683);
FORCEPROP 2 LAST CDS_LIB mstr_standard
J 2
(-2775 2675);
PAINT MONO (-2775 2675);
DISPLAY INVISIBLE (-2775 2675);
FORCEPROP 1 LAST BODY_TYPE PLUMBING
J 0
(-2775 2725);
DISPLAY 1.446809 (-2775 2725);
PAINT GREEN (-2775 2725);
DISPLAY INVISIBLE (-2775 2725);
FORCEPROP 1 LAST HDL_TAP TRUE
J 0
(-2450 2550);
DISPLAY 1.446809 (-2450 2550);
PAINT GREEN (-2450 2550);
DISPLAY INVISIBLE (-2450 2550);
FORCEPROP 1 LAST PATH I60
J 0
(-2777 2675);
DISPLAY 0.872340 (-2777 2675);
PAINT GREEN (-2777 2675);
DISPLAY INVISIBLE (-2777 2675);
FORCEADD TAP..1
(-2775 2775);
FORCEPROP 3 LASTPIN (-2825 2775) SIG_NAME P3E_CPU1_PE3_MP_TXN<11>
J 0
(-2815 2785);
DISPLAY 0.659574 (-2815 2785);
PAINT MONO (-2815 2785);
DISPLAY INVISIBLE (-2815 2785);
FORCEPROP 1 LASTPIN (-2825 2775) BN 11
J 0
(-2837 2783);
DISPLAY 0.617021 (-2837 2783);
PAINT GREEN (-2837 2783);
FORCEPROP 2 LAST CDS_LIB mstr_standard
J 2
(-2775 2775);
PAINT MONO (-2775 2775);
DISPLAY INVISIBLE (-2775 2775);
FORCEPROP 1 LAST BODY_TYPE PLUMBING
J 0
(-2775 2825);
DISPLAY 1.446809 (-2775 2825);
PAINT GREEN (-2775 2825);
DISPLAY INVISIBLE (-2775 2825);
FORCEPROP 1 LAST HDL_TAP TRUE
J 0
(-2450 2650);
DISPLAY 1.446809 (-2450 2650);
PAINT GREEN (-2450 2650);
DISPLAY INVISIBLE (-2450 2650);
FORCEPROP 1 LAST PATH I61
J 0
(-2777 2775);
DISPLAY 0.872340 (-2777 2775);
PAINT GREEN (-2777 2775);
DISPLAY INVISIBLE (-2777 2775);
FORCEADD TAP..1
(-2925 2925);
FORCEPROP 3 LASTPIN (-2975 2925) SIG_NAME P3E_CPU1_PE3_MP_TXP<9>
J 0
(-2965 2935);
DISPLAY 0.659574 (-2965 2935);
PAINT MONO (-2965 2935);
DISPLAY INVISIBLE (-2965 2935);
FORCEPROP 1 LASTPIN (-2975 2925) BN 9
J 0
(-2987 2933);
DISPLAY 0.617021 (-2987 2933);
PAINT GREEN (-2987 2933);
FORCEPROP 2 LAST CDS_LIB mstr_standard
J 2
(-2925 2925);
PAINT MONO (-2925 2925);
DISPLAY INVISIBLE (-2925 2925);
FORCEPROP 1 LAST BODY_TYPE PLUMBING
J 0
(-2925 2975);
DISPLAY 1.446809 (-2925 2975);
PAINT GREEN (-2925 2975);
DISPLAY INVISIBLE (-2925 2975);
FORCEPROP 1 LAST HDL_TAP TRUE
J 0
(-2600 2800);
DISPLAY 1.446809 (-2600 2800);
PAINT GREEN (-2600 2800);
DISPLAY INVISIBLE (-2600 2800);
FORCEPROP 1 LAST PATH I62
J 0
(-2927 2925);
DISPLAY 0.872340 (-2927 2925);
PAINT GREEN (-2927 2925);
DISPLAY INVISIBLE (-2927 2925);
FORCEADD TAP..1
(-2925 2875);
FORCEPROP 3 LASTPIN (-2975 2875) SIG_NAME P3E_CPU1_PE3_MP_TXP<8>
J 0
(-2965 2885);
DISPLAY 0.659574 (-2965 2885);
PAINT MONO (-2965 2885);
DISPLAY INVISIBLE (-2965 2885);
FORCEPROP 1 LASTPIN (-2975 2875) BN 8
J 0
(-2987 2883);
DISPLAY 0.617021 (-2987 2883);
PAINT GREEN (-2987 2883);
FORCEPROP 2 LAST CDS_LIB mstr_standard
J 2
(-2925 2875);
PAINT MONO (-2925 2875);
DISPLAY INVISIBLE (-2925 2875);
FORCEPROP 1 LAST BODY_TYPE PLUMBING
J 0
(-2925 2925);
DISPLAY 1.446809 (-2925 2925);
PAINT GREEN (-2925 2925);
DISPLAY INVISIBLE (-2925 2925);
FORCEPROP 1 LAST HDL_TAP TRUE
J 0
(-2600 2750);
DISPLAY 1.446809 (-2600 2750);
PAINT GREEN (-2600 2750);
DISPLAY INVISIBLE (-2600 2750);
FORCEPROP 1 LAST PATH I63
J 0
(-2927 2875);
DISPLAY 0.872340 (-2927 2875);
PAINT GREEN (-2927 2875);
DISPLAY INVISIBLE (-2927 2875);
FORCEADD TAP..1
(-2925 3025);
FORCEPROP 3 LASTPIN (-2975 3025) SIG_NAME P3E_CPU1_PE3_MP_TXP<11>
J 0
(-2965 3035);
DISPLAY 0.659574 (-2965 3035);
PAINT MONO (-2965 3035);
DISPLAY INVISIBLE (-2965 3035);
FORCEPROP 1 LASTPIN (-2975 3025) BN 11
J 0
(-2987 3033);
DISPLAY 0.617021 (-2987 3033);
PAINT GREEN (-2987 3033);
FORCEPROP 2 LAST CDS_LIB mstr_standard
J 2
(-2925 3025);
PAINT MONO (-2925 3025);
DISPLAY INVISIBLE (-2925 3025);
FORCEPROP 1 LAST BODY_TYPE PLUMBING
J 0
(-2925 3075);
DISPLAY 1.446809 (-2925 3075);
PAINT GREEN (-2925 3075);
DISPLAY INVISIBLE (-2925 3075);
FORCEPROP 1 LAST HDL_TAP TRUE
J 0
(-2600 2900);
DISPLAY 1.446809 (-2600 2900);
PAINT GREEN (-2600 2900);
DISPLAY INVISIBLE (-2600 2900);
FORCEPROP 1 LAST PATH I64
J 0
(-2927 3025);
DISPLAY 0.872340 (-2927 3025);
PAINT GREEN (-2927 3025);
DISPLAY INVISIBLE (-2927 3025);
FORCEADD TAP..1
(-2925 2975);
FORCEPROP 3 LASTPIN (-2975 2975) SIG_NAME P3E_CPU1_PE3_MP_TXP<10>
J 0
(-2965 2985);
DISPLAY 0.659574 (-2965 2985);
PAINT MONO (-2965 2985);
DISPLAY INVISIBLE (-2965 2985);
FORCEPROP 1 LASTPIN (-2975 2975) BN 10
J 0
(-2987 2983);
DISPLAY 0.617021 (-2987 2983);
PAINT GREEN (-2987 2983);
FORCEPROP 2 LAST CDS_LIB mstr_standard
J 2
(-2925 2975);
PAINT MONO (-2925 2975);
DISPLAY INVISIBLE (-2925 2975);
FORCEPROP 1 LAST BODY_TYPE PLUMBING
J 0
(-2925 3025);
DISPLAY 1.446809 (-2925 3025);
PAINT GREEN (-2925 3025);
DISPLAY INVISIBLE (-2925 3025);
FORCEPROP 1 LAST HDL_TAP TRUE
J 0
(-2600 2850);
DISPLAY 1.446809 (-2600 2850);
PAINT GREEN (-2600 2850);
DISPLAY INVISIBLE (-2600 2850);
FORCEPROP 1 LAST PATH I65
J 0
(-2927 2975);
DISPLAY 0.872340 (-2927 2975);
PAINT GREEN (-2927 2975);
DISPLAY INVISIBLE (-2927 2975);
FORCEADD TAP..1
(-2775 3125);
FORCEPROP 3 LASTPIN (-2825 3125) SIG_NAME P3E_CPU1_PE3_MP_TXN<12>
J 0
(-2815 3135);
DISPLAY 0.659574 (-2815 3135);
PAINT MONO (-2815 3135);
DISPLAY INVISIBLE (-2815 3135);
FORCEPROP 1 LASTPIN (-2825 3125) BN 12
J 0
(-2837 3133);
DISPLAY 0.617021 (-2837 3133);
PAINT GREEN (-2837 3133);
FORCEPROP 2 LAST CDS_LIB mstr_standard
J 2
(-2775 3125);
PAINT MONO (-2775 3125);
DISPLAY INVISIBLE (-2775 3125);
FORCEPROP 1 LAST BODY_TYPE PLUMBING
J 0
(-2775 3175);
DISPLAY 1.446809 (-2775 3175);
PAINT GREEN (-2775 3175);
DISPLAY INVISIBLE (-2775 3175);
FORCEPROP 1 LAST HDL_TAP TRUE
J 0
(-2450 3000);
DISPLAY 1.446809 (-2450 3000);
PAINT GREEN (-2450 3000);
DISPLAY INVISIBLE (-2450 3000);
FORCEPROP 1 LAST PATH I66
J 0
(-2777 3125);
DISPLAY 0.872340 (-2777 3125);
PAINT GREEN (-2777 3125);
DISPLAY INVISIBLE (-2777 3125);
FORCEADD TAP..1
(-2775 3175);
FORCEPROP 3 LASTPIN (-2825 3175) SIG_NAME P3E_CPU1_PE3_MP_TXN<13>
J 0
(-2815 3185);
DISPLAY 0.659574 (-2815 3185);
PAINT MONO (-2815 3185);
DISPLAY INVISIBLE (-2815 3185);
FORCEPROP 1 LASTPIN (-2825 3175) BN 13
J 0
(-2837 3183);
DISPLAY 0.617021 (-2837 3183);
PAINT GREEN (-2837 3183);
FORCEPROP 2 LAST CDS_LIB mstr_standard
J 2
(-2775 3175);
PAINT MONO (-2775 3175);
DISPLAY INVISIBLE (-2775 3175);
FORCEPROP 1 LAST BODY_TYPE PLUMBING
J 0
(-2775 3225);
DISPLAY 1.446809 (-2775 3225);
PAINT GREEN (-2775 3225);
DISPLAY INVISIBLE (-2775 3225);
FORCEPROP 1 LAST HDL_TAP TRUE
J 0
(-2450 3050);
DISPLAY 1.446809 (-2450 3050);
PAINT GREEN (-2450 3050);
DISPLAY INVISIBLE (-2450 3050);
FORCEPROP 1 LAST PATH I67
J 0
(-2777 3175);
DISPLAY 0.872340 (-2777 3175);
PAINT GREEN (-2777 3175);
DISPLAY INVISIBLE (-2777 3175);
FORCEADD TAP..1
(-2775 3225);
FORCEPROP 3 LASTPIN (-2825 3225) SIG_NAME P3E_CPU1_PE3_MP_TXN<14>
J 0
(-2815 3235);
DISPLAY 0.659574 (-2815 3235);
PAINT MONO (-2815 3235);
DISPLAY INVISIBLE (-2815 3235);
FORCEPROP 1 LASTPIN (-2825 3225) BN 14
J 0
(-2837 3233);
DISPLAY 0.617021 (-2837 3233);
PAINT GREEN (-2837 3233);
FORCEPROP 2 LAST CDS_LIB mstr_standard
J 2
(-2775 3225);
PAINT MONO (-2775 3225);
DISPLAY INVISIBLE (-2775 3225);
FORCEPROP 1 LAST BODY_TYPE PLUMBING
J 0
(-2775 3275);
DISPLAY 1.446809 (-2775 3275);
PAINT GREEN (-2775 3275);
DISPLAY INVISIBLE (-2775 3275);
FORCEPROP 1 LAST HDL_TAP TRUE
J 0
(-2450 3100);
DISPLAY 1.446809 (-2450 3100);
PAINT GREEN (-2450 3100);
DISPLAY INVISIBLE (-2450 3100);
FORCEPROP 1 LAST PATH I68
J 0
(-2777 3225);
DISPLAY 0.872340 (-2777 3225);
PAINT GREEN (-2777 3225);
DISPLAY INVISIBLE (-2777 3225);
FORCEADD TAP..1
(-2775 3275);
FORCEPROP 3 LASTPIN (-2825 3275) SIG_NAME P3E_CPU1_PE3_MP_TXN<15>
J 0
(-2815 3285);
DISPLAY 0.659574 (-2815 3285);
PAINT MONO (-2815 3285);
DISPLAY INVISIBLE (-2815 3285);
FORCEPROP 1 LASTPIN (-2825 3275) BN 15
J 0
(-2837 3283);
DISPLAY 0.617021 (-2837 3283);
PAINT GREEN (-2837 3283);
FORCEPROP 2 LAST CDS_LIB mstr_standard
J 2
(-2775 3275);
PAINT MONO (-2775 3275);
DISPLAY INVISIBLE (-2775 3275);
FORCEPROP 1 LAST BODY_TYPE PLUMBING
J 0
(-2775 3325);
DISPLAY 1.446809 (-2775 3325);
PAINT GREEN (-2775 3325);
DISPLAY INVISIBLE (-2775 3325);
FORCEPROP 1 LAST HDL_TAP TRUE
J 0
(-2450 3150);
DISPLAY 1.446809 (-2450 3150);
PAINT GREEN (-2450 3150);
DISPLAY INVISIBLE (-2450 3150);
FORCEPROP 1 LAST PATH I69
J 0
(-2777 3275);
DISPLAY 0.872340 (-2777 3275);
PAINT GREEN (-2777 3275);
DISPLAY INVISIBLE (-2777 3275);
FORCEADD TAP..1
(-2925 3425);
FORCEPROP 3 LASTPIN (-2975 3425) SIG_NAME P3E_CPU1_PE3_MP_TXP<13>
J 0
(-2965 3435);
DISPLAY 0.659574 (-2965 3435);
PAINT MONO (-2965 3435);
DISPLAY INVISIBLE (-2965 3435);
FORCEPROP 1 LASTPIN (-2975 3425) BN 13
J 0
(-2987 3433);
DISPLAY 0.617021 (-2987 3433);
PAINT GREEN (-2987 3433);
FORCEPROP 2 LAST CDS_LIB mstr_standard
J 2
(-2925 3425);
PAINT MONO (-2925 3425);
DISPLAY INVISIBLE (-2925 3425);
FORCEPROP 1 LAST BODY_TYPE PLUMBING
J 0
(-2925 3475);
DISPLAY 1.446809 (-2925 3475);
PAINT GREEN (-2925 3475);
DISPLAY INVISIBLE (-2925 3475);
FORCEPROP 1 LAST HDL_TAP TRUE
J 0
(-2600 3300);
DISPLAY 1.446809 (-2600 3300);
PAINT GREEN (-2600 3300);
DISPLAY INVISIBLE (-2600 3300);
FORCEPROP 1 LAST PATH I70
J 0
(-2927 3425);
DISPLAY 0.872340 (-2927 3425);
PAINT GREEN (-2927 3425);
DISPLAY INVISIBLE (-2927 3425);
FORCEADD TAP..1
(-2925 3375);
FORCEPROP 3 LASTPIN (-2975 3375) SIG_NAME P3E_CPU1_PE3_MP_TXP<12>
J 0
(-2965 3385);
DISPLAY 0.659574 (-2965 3385);
PAINT MONO (-2965 3385);
DISPLAY INVISIBLE (-2965 3385);
FORCEPROP 1 LASTPIN (-2975 3375) BN 12
J 0
(-2987 3383);
DISPLAY 0.617021 (-2987 3383);
PAINT GREEN (-2987 3383);
FORCEPROP 2 LAST CDS_LIB mstr_standard
J 2
(-2925 3375);
PAINT MONO (-2925 3375);
DISPLAY INVISIBLE (-2925 3375);
FORCEPROP 1 LAST BODY_TYPE PLUMBING
J 0
(-2925 3425);
DISPLAY 1.446809 (-2925 3425);
PAINT GREEN (-2925 3425);
DISPLAY INVISIBLE (-2925 3425);
FORCEPROP 1 LAST HDL_TAP TRUE
J 0
(-2600 3250);
DISPLAY 1.446809 (-2600 3250);
PAINT GREEN (-2600 3250);
DISPLAY INVISIBLE (-2600 3250);
FORCEPROP 1 LAST PATH I71
J 0
(-2927 3375);
DISPLAY 0.872340 (-2927 3375);
PAINT GREEN (-2927 3375);
DISPLAY INVISIBLE (-2927 3375);
FORCEADD TAP..1
(-2925 3475);
FORCEPROP 3 LASTPIN (-2975 3475) SIG_NAME P3E_CPU1_PE3_MP_TXP<14>
J 0
(-2965 3485);
DISPLAY 0.659574 (-2965 3485);
PAINT MONO (-2965 3485);
DISPLAY INVISIBLE (-2965 3485);
FORCEPROP 1 LASTPIN (-2975 3475) BN 14
J 0
(-2987 3483);
DISPLAY 0.617021 (-2987 3483);
PAINT GREEN (-2987 3483);
FORCEPROP 2 LAST CDS_LIB mstr_standard
J 2
(-2925 3475);
PAINT MONO (-2925 3475);
DISPLAY INVISIBLE (-2925 3475);
FORCEPROP 1 LAST BODY_TYPE PLUMBING
J 0
(-2925 3525);
DISPLAY 1.446809 (-2925 3525);
PAINT GREEN (-2925 3525);
DISPLAY INVISIBLE (-2925 3525);
FORCEPROP 1 LAST HDL_TAP TRUE
J 0
(-2600 3350);
DISPLAY 1.446809 (-2600 3350);
PAINT GREEN (-2600 3350);
DISPLAY INVISIBLE (-2600 3350);
FORCEPROP 1 LAST PATH I72
J 0
(-2927 3475);
DISPLAY 0.872340 (-2927 3475);
PAINT GREEN (-2927 3475);
DISPLAY INVISIBLE (-2927 3475);
FORCEADD TAP..1
(-2925 3525);
FORCEPROP 3 LASTPIN (-2975 3525) SIG_NAME P3E_CPU1_PE3_MP_TXP<15>
J 0
(-2965 3535);
DISPLAY 0.659574 (-2965 3535);
PAINT MONO (-2965 3535);
DISPLAY INVISIBLE (-2965 3535);
FORCEPROP 1 LASTPIN (-2975 3525) BN 15
J 0
(-2987 3533);
DISPLAY 0.617021 (-2987 3533);
PAINT GREEN (-2987 3533);
FORCEPROP 2 LAST CDS_LIB mstr_standard
J 2
(-2925 3525);
PAINT MONO (-2925 3525);
DISPLAY INVISIBLE (-2925 3525);
FORCEPROP 1 LAST BODY_TYPE PLUMBING
J 0
(-2925 3575);
DISPLAY 1.446809 (-2925 3575);
PAINT GREEN (-2925 3575);
DISPLAY INVISIBLE (-2925 3575);
FORCEPROP 1 LAST HDL_TAP TRUE
J 0
(-2600 3400);
DISPLAY 1.446809 (-2600 3400);
PAINT GREEN (-2600 3400);
DISPLAY INVISIBLE (-2600 3400);
FORCEPROP 1 LAST PATH I73
J 0
(-2927 3525);
DISPLAY 0.872340 (-2927 3525);
PAINT GREEN (-2927 3525);
DISPLAY INVISIBLE (-2927 3525);
FORCEADD OFFPAGE..1
(-6900 1525);
FORCEPROP 2 LAST $XR0 181 
J 0
(-7152 1525);
DISPLAY 0.638298 (-7152 1525);
PAINT MONO (-7152 1525);
FORCEPROP 2 LAST CDS_LIB mstr_standard
J 0
(-6900 1525);
PAINT ORANGE (-6900 1525);
DISPLAY INVISIBLE (-6900 1525);
FORCEPROP 1 LAST OFFPAGE TRUE
J 0
(-6575 1400);
DISPLAY 0.872340 (-6575 1400);
PAINT GREEN (-6575 1400);
DISPLAY INVISIBLE (-6575 1400);
FORCEPROP 1 LAST COMMENT_BODY TRUE
J 0
(-6775 1425);
DISPLAY 0.872340 (-6775 1425);
PAINT GREEN (-6775 1425);
DISPLAY INVISIBLE (-6775 1425);
FORCEPROP 2 LAST PATH I75
J 0
(-6850 1600);
DISPLAY 1.021277 (-6850 1600);
PAINT ORANGE (-6850 1600);
DISPLAY INVISIBLE (-6850 1600);
FORCEADD OFFPAGE..1
(-6900 1400);
FORCEPROP 2 LAST $XR0 181 
J 0
(-7152 1400);
DISPLAY 0.638298 (-7152 1400);
PAINT MONO (-7152 1400);
FORCEPROP 2 LAST CDS_LIB mstr_standard
J 0
(-6900 1400);
PAINT ORANGE (-6900 1400);
DISPLAY INVISIBLE (-6900 1400);
FORCEPROP 1 LAST OFFPAGE TRUE
J 0
(-6575 1275);
DISPLAY 0.872340 (-6575 1275);
PAINT GREEN (-6575 1275);
DISPLAY INVISIBLE (-6575 1275);
FORCEPROP 1 LAST COMMENT_BODY TRUE
J 0
(-6775 1300);
DISPLAY 0.872340 (-6775 1300);
PAINT GREEN (-6775 1300);
DISPLAY INVISIBLE (-6775 1300);
FORCEPROP 2 LAST PATH I76
J 0
(-6850 1475);
DISPLAY 1.021277 (-6850 1475);
PAINT ORANGE (-6850 1475);
DISPLAY INVISIBLE (-6850 1475);
FORCEADD OFFPAGE..2
(-1700 1475);
FORCEPROP 2 LAST $XR0 181 
J 0
(-1511 1475);
DISPLAY 0.638298 (-1511 1475);
PAINT MONO (-1511 1475);
FORCEPROP 2 LAST CDS_LIB mstr_standard
J 0
(-1700 1475);
PAINT ORANGE (-1700 1475);
DISPLAY INVISIBLE (-1700 1475);
FORCEPROP 1 LAST OFFPAGE TRUE
J 0
(-1375 1350);
DISPLAY 0.872340 (-1375 1350);
PAINT GREEN (-1375 1350);
DISPLAY INVISIBLE (-1375 1350);
FORCEPROP 1 LAST COMMENT_BODY TRUE
J 0
(-1745 1380);
DISPLAY 0.872340 (-1745 1380);
PAINT GREEN (-1745 1380);
DISPLAY INVISIBLE (-1745 1380);
FORCEPROP 2 LAST PATH I77
J 0
(-1650 1550);
DISPLAY 1.021277 (-1650 1550);
PAINT ORANGE (-1650 1550);
DISPLAY INVISIBLE (-1650 1550);
FORCEADD OFFPAGE..2
(-1700 1375);
FORCEPROP 2 LAST $XR0 181 
J 0
(-1511 1375);
DISPLAY 0.638298 (-1511 1375);
PAINT MONO (-1511 1375);
FORCEPROP 2 LAST CDS_LIB mstr_standard
J 0
(-1700 1375);
PAINT ORANGE (-1700 1375);
DISPLAY INVISIBLE (-1700 1375);
FORCEPROP 1 LAST OFFPAGE TRUE
J 0
(-1375 1250);
DISPLAY 0.872340 (-1375 1250);
PAINT GREEN (-1375 1250);
DISPLAY INVISIBLE (-1375 1250);
FORCEPROP 1 LAST COMMENT_BODY TRUE
J 0
(-1745 1280);
DISPLAY 0.872340 (-1745 1280);
PAINT GREEN (-1745 1280);
DISPLAY INVISIBLE (-1745 1280);
FORCEPROP 2 LAST PATH I78
J 0
(-1525 1450);
DISPLAY 1.021277 (-1525 1450);
PAINT ORANGE (-1525 1450);
DISPLAY INVISIBLE (-1525 1450);
FORCEADD OFFPAGE..2
(-1500 3625);
FORCEPROP 2 LAST $XR0 182 
J 0
(-1311 3625);
DISPLAY 0.638298 (-1311 3625);
PAINT MONO (-1311 3625);
FORCEPROP 2 LAST CDS_LIB mstr_standard
J 0
(-1500 3625);
PAINT ORANGE (-1500 3625);
DISPLAY INVISIBLE (-1500 3625);
FORCEPROP 1 LAST OFFPAGE TRUE
J 0
(-1175 3500);
DISPLAY 0.872340 (-1175 3500);
PAINT GREEN (-1175 3500);
DISPLAY INVISIBLE (-1175 3500);
FORCEPROP 1 LAST COMMENT_BODY TRUE
J 0
(-1545 3530);
DISPLAY 0.872340 (-1545 3530);
PAINT GREEN (-1545 3530);
DISPLAY INVISIBLE (-1545 3530);
FORCEPROP 2 LAST PATH I80
J 0
(-1325 3700);
DISPLAY 1.021277 (-1325 3700);
PAINT ORANGE (-1325 3700);
DISPLAY INVISIBLE (-1325 3700);
FORCEADD OFFPAGE..2
(-1500 3500);
FORCEPROP 2 LAST $XR0 182 
J 0
(-1311 3500);
DISPLAY 0.638298 (-1311 3500);
PAINT MONO (-1311 3500);
FORCEPROP 2 LAST CDS_LIB mstr_standard
J 0
(-1500 3500);
PAINT ORANGE (-1500 3500);
DISPLAY INVISIBLE (-1500 3500);
FORCEPROP 1 LAST OFFPAGE TRUE
J 0
(-1175 3375);
DISPLAY 0.872340 (-1175 3375);
PAINT GREEN (-1175 3375);
DISPLAY INVISIBLE (-1175 3375);
FORCEPROP 1 LAST COMMENT_BODY TRUE
J 0
(-1545 3405);
DISPLAY 0.872340 (-1545 3405);
PAINT GREEN (-1545 3405);
DISPLAY INVISIBLE (-1545 3405);
FORCEPROP 2 LAST PATH I81
J 0
(-1325 3575);
DISPLAY 1.021277 (-1325 3575);
PAINT ORANGE (-1325 3575);
DISPLAY INVISIBLE (-1325 3575);
FORCEADD OFFPAGE..1
(-6800 3700);
FORCEPROP 2 LAST $XR0 182 
J 0
(-7052 3700);
DISPLAY 0.638298 (-7052 3700);
PAINT MONO (-7052 3700);
FORCEPROP 2 LAST CDS_LIB mstr_standard
J 0
(-6800 3700);
PAINT ORANGE (-6800 3700);
DISPLAY INVISIBLE (-6800 3700);
FORCEPROP 1 LAST OFFPAGE TRUE
J 0
(-6475 3575);
DISPLAY 0.872340 (-6475 3575);
PAINT GREEN (-6475 3575);
DISPLAY INVISIBLE (-6475 3575);
FORCEPROP 1 LAST COMMENT_BODY TRUE
J 0
(-6675 3600);
DISPLAY 0.872340 (-6675 3600);
PAINT GREEN (-6675 3600);
DISPLAY INVISIBLE (-6675 3600);
FORCEPROP 2 LAST PATH I82
J 0
(-6750 3775);
DISPLAY 1.021277 (-6750 3775);
PAINT ORANGE (-6750 3775);
DISPLAY INVISIBLE (-6750 3775);
FORCEADD OFFPAGE..1
(-6800 3600);
FORCEPROP 2 LAST $XR0 182 
J 0
(-7052 3600);
DISPLAY 0.638298 (-7052 3600);
PAINT MONO (-7052 3600);
FORCEPROP 2 LAST CDS_LIB mstr_standard
J 0
(-6800 3600);
PAINT ORANGE (-6800 3600);
DISPLAY INVISIBLE (-6800 3600);
FORCEPROP 1 LAST OFFPAGE TRUE
J 0
(-6475 3475);
DISPLAY 0.872340 (-6475 3475);
PAINT GREEN (-6475 3475);
DISPLAY INVISIBLE (-6475 3475);
FORCEPROP 1 LAST COMMENT_BODY TRUE
J 0
(-6675 3500);
DISPLAY 0.872340 (-6675 3500);
PAINT GREEN (-6675 3500);
DISPLAY INVISIBLE (-6675 3500);
FORCEPROP 2 LAST PATH I83
J 0
(-6750 3675);
DISPLAY 1.021277 (-6750 3675);
PAINT ORANGE (-6750 3675);
DISPLAY INVISIBLE (-6750 3675);
FORCEADD SKX_EXT_B..12
(-4125 2575);
FORCEPROP 1 LAST LOCATION U2D1
J 0
(-4825 3775);
DISPLAY 0.617021 (-4825 3775);
PAINT AQUA (-4825 3775);
FORCEPROP 1 LAST PART_NUMBER TBD
J 0
(-4825 1425);
DISPLAY 0.617021 (-4825 1425);
PAINT BLUE (-4825 1425);
FORCEPROP 1 LAST MATERIAL IC
J 0
(-4825 3725);
DISPLAY 0.617021 (-4825 3725);
PAINT SKYBLUE (-4825 3725);
FORCEPROP 2 LASTPIN (-3375 3525) $PN CV5
J 0
(-3365 3535);
DISPLAY 0.617021 (-3365 3535);
PAINT ORANGE (-3365 3535);
FORCEPROP 2 LASTPIN (-3375 3475) $PN DA4
J 0
(-3365 3485);
DISPLAY 0.617021 (-3365 3485);
PAINT ORANGE (-3365 3485);
FORCEPROP 2 LASTPIN (-3375 3425) $PN DC6
J 0
(-3365 3435);
DISPLAY 0.617021 (-3365 3435);
PAINT ORANGE (-3365 3435);
FORCEPROP 2 LASTPIN (-3375 3375) $PN DG6
J 0
(-3365 3385);
DISPLAY 0.617021 (-3365 3385);
PAINT ORANGE (-3365 3385);
FORCEPROP 2 LASTPIN (-3375 3025) $PN DH5
J 0
(-3365 3035);
DISPLAY 0.617021 (-3365 3035);
PAINT ORANGE (-3365 3035);
FORCEPROP 2 LASTPIN (-3375 2975) $PN DK5
J 0
(-3365 2985);
DISPLAY 0.617021 (-3365 2985);
PAINT ORANGE (-3365 2985);
FORCEPROP 2 LASTPIN (-3375 2925) $PN DM5
J 0
(-3365 2935);
DISPLAY 0.617021 (-3365 2935);
PAINT ORANGE (-3365 2935);
FORCEPROP 2 LASTPIN (-3375 2875) $PN DN6
J 0
(-3365 2885);
DISPLAY 0.617021 (-3365 2885);
PAINT ORANGE (-3365 2885);
FORCEPROP 2 LASTPIN (-3375 2525) $PN DP7
J 0
(-3365 2535);
DISPLAY 0.617021 (-3365 2535);
PAINT ORANGE (-3365 2535);
FORCEPROP 2 LASTPIN (-3375 2475) $PN DT9
J 0
(-3365 2485);
DISPLAY 0.617021 (-3365 2485);
PAINT ORANGE (-3365 2485);
FORCEPROP 2 LASTPIN (-3375 2425) $PN DV9
J 0
(-3365 2435);
DISPLAY 0.617021 (-3365 2435);
PAINT ORANGE (-3365 2435);
FORCEPROP 2 LASTPIN (-3375 2375) $PN DY9
J 0
(-3365 2385);
DISPLAY 0.617021 (-3365 2385);
PAINT ORANGE (-3365 2385);
FORCEPROP 2 LASTPIN (-3375 2025) $PN EA10
J 0
(-3365 2035);
DISPLAY 0.617021 (-3365 2035);
PAINT ORANGE (-3365 2035);
FORCEPROP 2 LASTPIN (-3375 1975) $PN EB11
J 0
(-3365 1985);
DISPLAY 0.617021 (-3365 1985);
PAINT ORANGE (-3365 1985);
FORCEPROP 2 LASTPIN (-3375 1925) $PN ED13
J 0
(-3365 1935);
DISPLAY 0.617021 (-3365 1935);
PAINT ORANGE (-3365 1935);
FORCEPROP 2 LASTPIN (-3375 1875) $PN EC14
J 0
(-3365 1885);
DISPLAY 0.617021 (-3365 1885);
PAINT ORANGE (-3365 1885);
FORCEPROP 2 LASTPIN (-3375 3275) $PN CY5
J 0
(-3365 3285);
DISPLAY 0.617021 (-3365 3285);
PAINT ORANGE (-3365 3285);
FORCEPROP 2 LASTPIN (-3375 3225) $PN DB5
J 0
(-3365 3235);
DISPLAY 0.617021 (-3365 3235);
PAINT ORANGE (-3365 3235);
FORCEPROP 2 LASTPIN (-3375 3175) $PN DD5
J 0
(-3365 3185);
DISPLAY 0.617021 (-3365 3185);
PAINT ORANGE (-3365 3185);
FORCEPROP 2 LASTPIN (-3375 3125) $PN DJ6
J 0
(-3365 3135);
DISPLAY 0.617021 (-3365 3135);
PAINT ORANGE (-3365 3135);
FORCEPROP 2 LASTPIN (-3375 2775) $PN DJ4
J 0
(-3365 2785);
DISPLAY 0.617021 (-3365 2785);
PAINT ORANGE (-3365 2785);
FORCEPROP 2 LASTPIN (-3375 2725) $PN DL6
J 0
(-3365 2735);
DISPLAY 0.617021 (-3365 2735);
PAINT ORANGE (-3365 2735);
FORCEPROP 2 LASTPIN (-3375 2675) $PN DP5
J 0
(-3365 2685);
DISPLAY 0.617021 (-3365 2685);
PAINT ORANGE (-3365 2685);
FORCEPROP 2 LASTPIN (-3375 2625) $PN DM7
J 0
(-3365 2635);
DISPLAY 0.617021 (-3365 2635);
PAINT ORANGE (-3365 2635);
FORCEPROP 2 LASTPIN (-3375 2275) $PN DR8
J 0
(-3365 2285);
DISPLAY 0.617021 (-3365 2285);
PAINT ORANGE (-3365 2285);
FORCEPROP 2 LASTPIN (-3375 2225) $PN DU8
J 0
(-3365 2235);
DISPLAY 0.617021 (-3365 2235);
PAINT ORANGE (-3365 2235);
FORCEPROP 2 LASTPIN (-3375 2175) $PN DW10
J 0
(-3365 2185);
DISPLAY 0.617021 (-3365 2185);
PAINT ORANGE (-3365 2185);
FORCEPROP 2 LASTPIN (-3375 2125) $PN EB9
J 0
(-3365 2135);
DISPLAY 0.617021 (-3365 2135);
PAINT ORANGE (-3365 2135);
FORCEPROP 2 LASTPIN (-3375 1775) $PN DY11
J 0
(-3365 1785);
DISPLAY 0.617021 (-3365 1785);
PAINT ORANGE (-3365 1785);
FORCEPROP 2 LASTPIN (-3375 1725) $PN EC12
J 0
(-3365 1735);
DISPLAY 0.617021 (-3365 1735);
PAINT ORANGE (-3365 1735);
FORCEPROP 2 LASTPIN (-3375 1675) $PN EE12
J 0
(-3365 1685);
DISPLAY 0.617021 (-3365 1685);
PAINT ORANGE (-3365 1685);
FORCEPROP 2 LASTPIN (-3375 1625) $PN EE14
J 0
(-3365 1635);
DISPLAY 0.617021 (-3365 1635);
PAINT ORANGE (-3365 1635);
FORCEPROP 2 LASTPIN (-4875 3525) $PN CU10
J 2
(-4885 3535);
DISPLAY 0.617021 (-4885 3535);
PAINT ORANGE (-4885 3535);
FORCEPROP 2 LASTPIN (-4875 3475) $PN CW10
J 2
(-4885 3485);
DISPLAY 0.617021 (-4885 3485);
PAINT ORANGE (-4885 3485);
FORCEPROP 2 LASTPIN (-4875 3425) $PN DA12
J 2
(-4885 3435);
DISPLAY 0.617021 (-4885 3435);
PAINT ORANGE (-4885 3435);
FORCEPROP 2 LASTPIN (-4875 3375) $PN DC12
J 2
(-4885 3385);
DISPLAY 0.617021 (-4885 3385);
PAINT ORANGE (-4885 3385);
FORCEPROP 2 LASTPIN (-4875 3025) $PN DF11
J 2
(-4885 3035);
DISPLAY 0.617021 (-4885 3035);
PAINT ORANGE (-4885 3035);
FORCEPROP 2 LASTPIN (-4875 2975) $PN DE12
J 2
(-4885 2985);
DISPLAY 0.617021 (-4885 2985);
PAINT ORANGE (-4885 2985);
FORCEPROP 2 LASTPIN (-4875 2925) $PN DH11
J 2
(-4885 2935);
DISPLAY 0.617021 (-4885 2935);
PAINT ORANGE (-4885 2935);
FORCEPROP 2 LASTPIN (-4875 2875) $PN DK13
J 2
(-4885 2885);
DISPLAY 0.617021 (-4885 2885);
PAINT ORANGE (-4885 2885);
FORCEPROP 2 LASTPIN (-4875 2525) $PN DJ14
J 2
(-4885 2535);
DISPLAY 0.617021 (-4885 2535);
PAINT ORANGE (-4885 2535);
FORCEPROP 2 LASTPIN (-4875 2475) $PN DM13
J 2
(-4885 2485);
DISPLAY 0.617021 (-4885 2485);
PAINT ORANGE (-4885 2485);
FORCEPROP 2 LASTPIN (-4875 2425) $PN DP15
J 2
(-4885 2435);
DISPLAY 0.617021 (-4885 2435);
PAINT ORANGE (-4885 2435);
FORCEPROP 2 LASTPIN (-4875 2375) $PN DN16
J 2
(-4885 2385);
DISPLAY 0.617021 (-4885 2385);
PAINT ORANGE (-4885 2385);
FORCEPROP 2 LASTPIN (-4875 2025) $PN DR18
J 2
(-4885 2035);
DISPLAY 0.617021 (-4885 2035);
PAINT ORANGE (-4885 2035);
FORCEPROP 2 LASTPIN (-4875 1975) $PN DV17
J 2
(-4885 1985);
DISPLAY 0.617021 (-4885 1985);
PAINT ORANGE (-4885 1985);
FORCEPROP 2 LASTPIN (-4875 1925) $PN DU18
J 2
(-4885 1935);
DISPLAY 0.617021 (-4885 1935);
PAINT ORANGE (-4885 1935);
FORCEPROP 2 LASTPIN (-4875 1875) $PN DY17
J 2
(-4885 1885);
DISPLAY 0.617021 (-4885 1885);
PAINT ORANGE (-4885 1885);
FORCEPROP 2 LASTPIN (-4875 3275) $PN CV9
J 2
(-4885 3285);
DISPLAY 0.617021 (-4885 3285);
PAINT ORANGE (-4885 3285);
FORCEPROP 2 LASTPIN (-4875 3225) $PN CY11
J 2
(-4885 3235);
DISPLAY 0.617021 (-4885 3235);
PAINT ORANGE (-4885 3235);
FORCEPROP 2 LASTPIN (-4875 3175) $PN DB11
J 2
(-4885 3185);
DISPLAY 0.617021 (-4885 3185);
PAINT ORANGE (-4885 3185);
FORCEPROP 2 LASTPIN (-4875 3125) $PN DD13
J 2
(-4885 3135);
DISPLAY 0.617021 (-4885 3135);
PAINT ORANGE (-4885 3135);
FORCEPROP 2 LASTPIN (-4875 2775) $PN DG10
J 2
(-4885 2785);
DISPLAY 0.617021 (-4885 2785);
PAINT ORANGE (-4885 2785);
FORCEPROP 2 LASTPIN (-4875 2725) $PN DG12
J 2
(-4885 2735);
DISPLAY 0.617021 (-4885 2735);
PAINT ORANGE (-4885 2735);
FORCEPROP 2 LASTPIN (-4875 2675) $PN DJ12
J 2
(-4885 2685);
DISPLAY 0.617021 (-4885 2685);
PAINT ORANGE (-4885 2685);
FORCEPROP 2 LASTPIN (-4875 2625) $PN DL12
J 2
(-4885 2635);
DISPLAY 0.617021 (-4885 2635);
PAINT ORANGE (-4885 2635);
FORCEPROP 2 LASTPIN (-4875 2275) $PN DL14
J 2
(-4885 2285);
DISPLAY 0.617021 (-4885 2285);
PAINT ORANGE (-4885 2285);
FORCEPROP 2 LASTPIN (-4875 2225) $PN DN14
J 2
(-4885 2235);
DISPLAY 0.617021 (-4885 2235);
PAINT ORANGE (-4885 2235);
FORCEPROP 2 LASTPIN (-4875 2175) $PN DR14
J 2
(-4885 2185);
DISPLAY 0.617021 (-4885 2185);
PAINT ORANGE (-4885 2185);
FORCEPROP 2 LASTPIN (-4875 2125) $PN DR16
J 2
(-4885 2135);
DISPLAY 0.617021 (-4885 2135);
PAINT ORANGE (-4885 2135);
FORCEPROP 2 LASTPIN (-4875 1775) $PN DT19
J 2
(-4885 1785);
DISPLAY 0.617021 (-4885 1785);
PAINT ORANGE (-4885 1785);
FORCEPROP 2 LASTPIN (-4875 1725) $PN DW16
J 2
(-4885 1735);
DISPLAY 0.617021 (-4885 1735);
PAINT ORANGE (-4885 1735);
FORCEPROP 2 LASTPIN (-4875 1675) $PN DW18
J 2
(-4885 1685);
DISPLAY 0.617021 (-4885 1685);
PAINT ORANGE (-4885 1685);
FORCEPROP 2 LASTPIN (-4875 1625) $PN EA18
J 2
(-4885 1635);
DISPLAY 0.617021 (-4885 1635);
PAINT ORANGE (-4885 1635);
FORCEPROP 1 LAST PACK_TYPE BGA1
J 0
(-4825 3825);
PAINT SKYBLUE (-4825 3825);
DISPLAY INVISIBLE (-4825 3825);
FORCEPROP 2 LAST SEC_TYPE BGA1
J 0
(-4825 3825);
DISPLAY 1.021277 (-4825 3825);
PAINT ORANGE (-4825 3825);
DISPLAY INVISIBLE (-4825 3825);
FORCEPROP 2 LAST CDS_LIB chpset_lib
J 0
(-4125 2575);
PAINT ORANGE (-4125 2575);
DISPLAY INVISIBLE (-4125 2575);
FORCEPROP 2 LAST SEC 12
J 0
(-4825 3825);
DISPLAY 0.680851 (-4825 3825);
PAINT MONO (-4825 3825);
DISPLAY INVISIBLE (-4825 3825);
FORCEPROP 2 LAST CDS_LOCATION U2D1
J 0
(-4825 3775);
DISPLAY 0.617021 (-4825 3775);
PAINT AQUA (-4825 3775);
DISPLAY INVISIBLE (-4825 3775);
FORCEPROP 1 LAST PATH I84
J 0
(-4125 3725);
PAINT GREEN (-4125 3725);
DISPLAY INVISIBLE (-4125 3725);
FORCEADD DESIGN_NOTE..1
(-4625 1325);
FORCEPROP 0 LAST L1 CPU SYMBOLS 1-30 ARE PRELIMINARY AND SUBJECT TO CHANGE
J 0
(-4825 1200);
DISPLAY 1.021277 (-4825 1200);
PAINT ORANGE (-4825 1200);
FORCEPROP 2 LAST CDS_LIB mstr_symbols
J 0
(-4625 1325);
PAINT ORANGE (-4625 1325);
DISPLAY INVISIBLE (-4625 1325);
FORCEPROP 1 LAST COMMENT_BODY TRUE
J 0
(-4600 1425);
DISPLAY 0.978723 (-4600 1425);
PAINT ORANGE (-4600 1425);
DISPLAY INVISIBLE (-4600 1425);
FORCEADD PRELIM..10
(-4115 2565);
PAINT GRAY (-4115 2565);
FORCEPROP 2 LAST CDS_LIB mstr_misc
J 0
(-4115 2565);
PAINT ORANGE (-4115 2565);
DISPLAY INVISIBLE (-4115 2565);
FORCEPROP 1 LAST COMMENT_BODY TRUE
J 0
(-4115 2565);
PAINT ORANGE (-4115 2565);
DISPLAY INVISIBLE (-4115 2565);
FORCEADD INTEL_CORP_BPAGE..1
(0 0);
FORCEPROP 1 LAST CDS_CON_LAST_MODIFIED Tue Dec 01 11:51:37 2015
J 0
(-1425 325);
DISPLAY 1.340426 (-1425 325);
PAINT GREEN (-1425 325);
DISPLAY INVISIBLE (-1425 325);
FORCEPROP 1 LAST CUSTOM_TXT_CDS <CURRENT_DESIGN_SHEET> OF <TOTAL_DESIGN_SHEETS>
J 0
(-500 25);
PAINT GREEN (-500 25);
FORCEPROP 1 LAST CUSTOM_TXT_CDS <CON_LAST_MODIFIED>
J 0
(-1925 350);
PAINT GREEN (-1925 350);
FORCEPROP 2 LAST CUSTOM_TXT_CDS <XR_PAGE_TITLE>
J 0
(-7890 5250);
DISPLAY 0.638298 (-7890 5250);
PAINT PINK (-7890 5250);
DISPLAY INVISIBLE (-7890 5250);
FORCEPROP 1 LAST SCH_ADDRESS3 Santa Clara, CA 95052-8119
J 0
(-3975 25);
DISPLAY 0.617021 (-3975 25);
PAINT GREEN (-3975 25);
FORCEPROP 1 LAST SCH_ADDRESS2 P.O. BOX 58119
J 0
(-3975 75);
DISPLAY 0.617021 (-3975 75);
PAINT GREEN (-3975 75);
FORCEPROP 1 LAST SCH_ADDRESS1 2200 Mission College Blvd.
J 0
(-3975 125);
DISPLAY 0.617021 (-3975 125);
PAINT GREEN (-3975 125);
FORCEPROP 1 LAST SCH_TITLE SKYLAKE - SKT1 - 12 OF 21
J 0
(-7950 50);
DISPLAY 1.212766 (-7950 50);
PAINT GREEN (-7950 50);
FORCEPROP 1 LAST SCH_NUMBER H4694802
J 0
(-1300 150);
DISPLAY 1.212766 (-1300 150);
PAINT YELLOW (-1300 150);
FORCEPROP 1 LAST SCH_DEPT BESD
J 1
(-4450 100);
DISPLAY 1.212766 (-4450 100);
PAINT YELLOW (-4450 100);
FORCEPROP 1 LAST SCH_REV 2.420
J 0
(-250 150);
DISPLAY 0.978723 (-250 150);
PAINT YELLOW (-250 150);
FORCEPROP 2 LAST PAGE_BORDER TRUE
J 0
(-7890 5250);
DISPLAY 0.851064 (-7890 5250);
PAINT PINK (-7890 5250);
DISPLAY INVISIBLE (-7890 5250);
FORCEPROP 2 LAST CDS_LIB mstr_symbols
J 0
(0 0);
PAINT ORANGE (0 0);
DISPLAY INVISIBLE (0 0);
FORCEPROP 1 LAST COMMENT_BODY TRUE
J 0
(12 12);
DISPLAY 0.638298 (12 12);
PAINT GREEN (12 12);
DISPLAY INVISIBLE (12 12);
FORCEPROP 2 LAST CDS_XR_PAGE_TITLE CR-66 : @BASEBOARD_FAB2_LIB.BASEBOARD_FAB2(SCH_1):PAGE66
J 0
(-7890 5250);
DISPLAY 0.638298 (-7890 5250);
PAINT PINK (-7890 5250);
DISPLAY INVISIBLE (-7890 5250);
WIRE 17 -1 (-2725 3300)(-2725 3500);
WIRE 17 -1 (-2725 3250)(-2725 3300);
WIRE 17 -1 (-2725 3500)(-1550 3500);
FORCEPROP 2 LAST SIG_NAME P3E_CPU1_PE3_MP_TXN<15:8>
J 0
(-2185 3510);
DISPLAY 0.617021 (-2185 3510);
PAINT ORANGE (-2185 3510);
WIRE 17 -1 (-2725 3200)(-2725 3250);
WIRE 17 -1 (-2725 3150)(-2725 3200);
WIRE 17 -1 (-2725 2800)(-2725 3150);
WIRE 17 -1 (-2725 2750)(-2725 2800);
WIRE 17 -1 (-2725 2700)(-2725 2750);
WIRE 17 -1 (-2725 2650)(-2725 2700);
WIRE 17 -1 (-2725 2250)(-2725 2300);
WIRE 17 -1 (-2725 2200)(-2725 2250);
WIRE 17 -1 (-2725 2150)(-2725 2200);
WIRE 17 -1 (-2725 1800)(-2725 2150);
WIRE 17 -1 (-2725 1750)(-2725 1800);
WIRE 17 -1 (-2725 1700)(-2725 1750);
WIRE 17 -1 (-2725 1700)(-2725 1650);
WIRE 17 -1 (-2725 1650)(-2725 1475);
WIRE 17 -1 (-2725 1475)(-1750 1475);
FORCEPROP 2 LAST SIG_NAME P3E_CPU1_PE3_MP_TXN<7:0>
J 0
(-2460 1485);
DISPLAY 0.617021 (-2460 1485);
PAINT ORANGE (-2460 1485);
WIRE 17 -1 (-2875 3550)(-2875 3625);
WIRE 17 -1 (-2875 3500)(-2875 3550);
WIRE 17 -1 (-2875 3625)(-1550 3625);
FORCEPROP 2 LAST SIG_NAME P3E_CPU1_PE3_MP_TXP<15:8>
J 0
(-2185 3635);
DISPLAY 0.617021 (-2185 3635);
PAINT ORANGE (-2185 3635);
WIRE 17 -1 (-2875 3450)(-2875 3500);
WIRE 17 -1 (-2875 3450)(-2875 3400);
WIRE 17 -1 (-2875 3050)(-2875 3400);
WIRE 17 -1 (-2875 3000)(-2875 3050);
WIRE 17 -1 (-2875 2950)(-2875 3000);
WIRE 17 -1 (-2875 2900)(-2875 2950);
WIRE 17 -1 (-2875 2500)(-2875 2550);
WIRE 17 -1 (-2875 2450)(-2875 2500);
WIRE 17 -1 (-2875 2400)(-2875 2450);
WIRE 17 -1 (-2875 2050)(-2875 2400);
WIRE 17 -1 (-2875 2000)(-2875 2050);
WIRE 17 -1 (-2875 1950)(-2875 2000);
WIRE 17 -1 (-2875 1900)(-2875 1950);
WIRE 17 -1 (-2875 1900)(-2875 1375);
WIRE 17 -1 (-2875 1375)(-1750 1375);
FORCEPROP 2 LAST SIG_NAME P3E_CPU1_PE3_MP_TXP<7:0>
J 0
(-2460 1385);
DISPLAY 0.617021 (-2460 1385);
PAINT ORANGE (-2460 1385);
WIRE 17 -1 (-5600 3300)(-5600 3400);
WIRE 17 -1 (-5600 3250)(-5600 3300);
WIRE 17 -1 (-5600 3400)(-5600 3600);
WIRE 17 -1 (-6750 3600)(-5600 3600);
FORCEPROP 2 LAST SIG_NAME P3E_CPU1_PE3_MP_RXN<15:8>
J 0
(-6710 3610);
DISPLAY 0.617021 (-6710 3610);
PAINT ORANGE (-6710 3610);
WIRE 17 -1 (-5600 3200)(-5600 3250);
WIRE 17 -1 (-5600 3200)(-5600 2800);
WIRE 17 -1 (-5600 2800)(-5600 2750);
WIRE 17 -1 (-5600 2750)(-5600 2700);
WIRE 17 -1 (-5450 3450)(-5450 3150);
WIRE 17 -1 (-5450 3500)(-5450 3450);
WIRE 17 -1 (-5450 3150)(-5450 3050);
WIRE 17 -1 (-5450 3050)(-5450 3000);
WIRE 17 -1 (-5450 3550)(-5450 3500);
WIRE 17 -1 (-5450 3700)(-5450 3550);
WIRE 17 -1 (-5450 3000)(-5450 2950);
WIRE 17 -1 (-5450 2950)(-5450 2900);
WIRE 17 -1 (-6750 3700)(-5450 3700);
FORCEPROP 2 LAST SIG_NAME P3E_CPU1_PE3_MP_RXP<15:8>
J 0
(-6710 3710);
DISPLAY 0.617021 (-6710 3710);
PAINT ORANGE (-6710 3710);
WIRE 17 -1 (-5600 2700)(-5600 2650);
WIRE 17 -1 (-5600 2250)(-5600 2300);
WIRE 17 -1 (-5600 2200)(-5600 2250);
WIRE 17 -1 (-5600 2200)(-5600 2150);
WIRE 17 -1 (-5600 2150)(-5600 1800);
WIRE 17 -1 (-5600 1800)(-5600 1750);
WIRE 17 -1 (-5600 1750)(-5600 1700);
WIRE 17 -1 (-5600 1700)(-5600 1650);
WIRE 17 -1 (-5600 1650)(-5600 1525);
WIRE 17 -1 (-6850 1525)(-5600 1525);
FORCEPROP 2 LAST SIG_NAME P3E_CPU1_PE3_MP_RXN<7:0>
J 0
(-6810 1535);
DISPLAY 0.617021 (-6810 1535);
PAINT ORANGE (-6810 1535);
WIRE 17 -1 (-5450 2550)(-5450 2500);
WIRE 17 -1 (-5450 2500)(-5450 2450);
WIRE 17 -1 (-5450 2450)(-5450 2400);
WIRE 17 -1 (-5450 2050)(-5450 2400);
WIRE 17 -1 (-5450 2000)(-5450 2050);
WIRE 17 -1 (-5450 2000)(-5450 1950);
WIRE 17 -1 (-5450 1950)(-5450 1900);
WIRE 17 -1 (-5450 1900)(-5450 1400);
WIRE 17 -1 (-6850 1400)(-5450 1400);
FORCEPROP 2 LAST SIG_NAME P3E_CPU1_PE3_MP_RXP<7:0>
J 0
(-6810 1410);
DISPLAY 0.617021 (-6810 1410);
PAINT ORANGE (-6810 1410);
WIRE 16 -1 (-5350 1875)(-4875 1875);
WIRE 16 -1 (-5350 1925)(-4875 1925);
WIRE 16 -1 (-5350 1975)(-4875 1975);
WIRE 16 -1 (-5350 2025)(-4875 2025);
WIRE 16 -1 (-4875 1625)(-5500 1625);
WIRE 16 -1 (-4875 1675)(-5500 1675);
WIRE 16 -1 (-4875 1725)(-5500 1725);
WIRE 16 -1 (-4875 1775)(-5500 1775);
WIRE 16 -1 (-4875 2375)(-5350 2375);
WIRE 16 -1 (-5350 2425)(-4875 2425);
WIRE 16 -1 (-5350 2475)(-4875 2475);
WIRE 16 -1 (-5350 2525)(-4875 2525);
WIRE 16 -1 (-5350 2875)(-4875 2875);
WIRE 16 -1 (-5350 2925)(-4875 2925);
WIRE 16 -1 (-5350 2975)(-4875 2975);
WIRE 16 -1 (-5350 3025)(-4875 3025);
WIRE 16 -1 (-5500 3375)(-4875 3375);
WIRE 16 -1 (-5350 3425)(-4875 3425);
WIRE 16 -1 (-5350 3475)(-4875 3475);
WIRE 16 -1 (-5350 3525)(-4875 3525);
WIRE 16 -1 (-4875 2125)(-5500 2125);
WIRE 16 -1 (-5500 2175)(-4875 2175);
WIRE 16 -1 (-5500 2225)(-4875 2225);
WIRE 16 -1 (-5500 2275)(-4875 2275);
WIRE 16 -1 (-5500 2625)(-4875 2625);
WIRE 16 -1 (-5500 2675)(-4875 2675);
WIRE 16 -1 (-5500 2725)(-4875 2725);
WIRE 16 -1 (-5500 2775)(-4875 2775);
WIRE 16 -1 (-5350 3125)(-4875 3125);
WIRE 16 -1 (-5500 3175)(-4875 3175);
WIRE 16 -1 (-5500 3225)(-4875 3225);
WIRE 16 -1 (-5500 3275)(-4875 3275);
WIRE 16 -1 (-3375 1875)(-2975 1875);
WIRE 16 -1 (-2975 1925)(-3375 1925);
WIRE 16 -1 (-3375 1975)(-2975 1975);
WIRE 16 -1 (-2975 2025)(-3375 2025);
WIRE 16 -1 (-2825 1625)(-3375 1625);
WIRE 16 -1 (-2825 1675)(-3375 1675);
WIRE 16 -1 (-2825 1725)(-3375 1725);
WIRE 16 -1 (-2825 1775)(-3375 1775);
WIRE 16 -1 (-2975 2375)(-3375 2375);
WIRE 16 -1 (-2975 2425)(-3375 2425);
WIRE 16 -1 (-2975 2475)(-3375 2475);
WIRE 16 -1 (-2975 2525)(-3375 2525);
WIRE 16 -1 (-2975 2875)(-3375 2875);
WIRE 16 -1 (-2975 2925)(-3375 2925);
WIRE 16 -1 (-2975 2975)(-3375 2975);
WIRE 16 -1 (-2975 3025)(-3375 3025);
WIRE 16 -1 (-2975 3375)(-3375 3375);
WIRE 16 -1 (-3375 3425)(-2975 3425);
WIRE 16 -1 (-3375 3475)(-2975 3475);
WIRE 16 -1 (-2975 3525)(-3375 3525);
WIRE 16 -1 (-2825 2125)(-3375 2125);
WIRE 16 -1 (-2825 2175)(-3375 2175);
WIRE 16 -1 (-3375 2225)(-2825 2225);
WIRE 16 -1 (-3375 2275)(-2825 2275);
WIRE 16 -1 (-2825 2625)(-3375 2625);
WIRE 16 -1 (-3375 2675)(-2825 2675);
WIRE 16 -1 (-2825 2725)(-3375 2725);
WIRE 16 -1 (-2825 2775)(-3375 2775);
WIRE 16 -1 (-3375 3125)(-2825 3125);
WIRE 16 -1 (-2825 3175)(-3375 3175);
WIRE 16 -1 (-2825 3225)(-3375 3225);
WIRE 16 -1 (-2825 3275)(-3375 3275);
FORCENOTE
POLARITY SWAPED P3E_CPU1_PE3_MP_RX*<12>
(-7550 3325) 0;
DISPLAY LEFT (-7550 3325);
DISPLAY 1.021277 (-7550 3325);
PAINT PURPLE (-7550 3325);
FORCENOTE
DE NOTE:
(-7550 3400) 0;
DISPLAY LEFT (-7550 3400);
DISPLAY 1.021277 (-7550 3400);
PAINT PURPLE (-7550 3400);
FORCENOTE
BOM_COST=PROC_SOCKET
(-7925 225) 0;
DISPLAY LEFT (-7925 225);
DISPLAY 1.723404 (-7925 225);
PAINT PURPLE (-7925 225);
FORCENOTE
ROOM=CPU1
(-7925 350) 0;
DISPLAY LEFT (-7925 350);
DISPLAY 1.723404 (-7925 350);
PAINT PURPLE (-7925 350);
QUIT
